G04 ================== begin FILE IDENTIFICATION RECORD ==================*
G04 Layout Name:  15669-1.brd*
G04 Film Name:    DRILL*
G04 File Format:  Gerber RS274X*
G04 File Origin:  Cadence Allegro 16.5-S056*
G04 Origin Date:  Wed Nov 16 04:08:10 2016*
G04 *
G04 Layer:  MANUFACTURING/NCLEGEND-1-8*
G04 Layer:  MANUFACTURING/DRILL SIZE*
G04 Layer:  DRAWING FORMAT/LAYER_PCB_STORY*
G04 Layer:  DRAWING FORMAT/LAYER_DRILL*
G04 Layer:  BOARD GEOMETRY/PANEL_OUTLINE*
G04 *
G04 Offset:    (0.00 0.00)*
G04 Mirror:    No*
G04 Mode:      Positive*
G04 Rotation:  0*
G04 FullContactRelief:  No*
G04 UndefLineWidth:     6.00*
G04 ================== end FILE IDENTIFICATION RECORD ====================*
%FSLAX35Y35*MOIN*%
%IR0*IPPOS*OFA0.00000B0.00000*MIA0B0*SFA1.00000B1.00000*%
%AMMACRO14*
1,1,.006,-.032625,.010875*
20,1,.006,-.032625,.010875,-.032129,.01654,0.0*
1,1,.006,-.032129,.01654*
20,1,.006,-.032129,.01654,-.030657,.022033,0.0*
1,1,.006,-.030657,.022033*
20,1,.006,-.030657,.022033,-.028254,.027187,0.0*
1,1,.006,-.028254,.027187*
20,1,.006,-.028254,.027187,-.024992,.031846,0.0*
1,1,.006,-.024992,.031846*
20,1,.006,-.024992,.031846,-.020971,.035867,0.0*
1,1,.006,-.020971,.035867*
20,1,.006,-.020971,.035867,-.016313,.039129,0.0*
1,1,.006,-.016313,.039129*
20,1,.006,-.016313,.039129,-.011158,.041532,0.0*
1,1,.006,-.011158,.041532*
20,1,.006,-.011158,.041532,-.005665,.043004,0.0*
1,1,.006,-.005665,.043004*
20,1,.006,-.005665,.043004,0.0,.0435,0.0*
1,1,.006,0.0,.0435*
20,1,.006,0.0,.0435,.005665,.043004,0.0*
1,1,.006,.005665,.043004*
20,1,.006,.005665,.043004,.011158,.041532,0.0*
1,1,.006,.011158,.041532*
20,1,.006,.011158,.041532,.016312,.039129,0.0*
1,1,.006,.016312,.039129*
20,1,.006,.016312,.039129,.020971,.035867,0.0*
1,1,.006,.020971,.035867*
20,1,.006,.020971,.035867,.024992,.031846,0.0*
1,1,.006,.024992,.031846*
20,1,.006,.024992,.031846,.028254,.027188,0.0*
1,1,.006,.028254,.027188*
20,1,.006,.028254,.027188,.030657,.022033,0.0*
1,1,.006,.030657,.022033*
20,1,.006,.030657,.022033,.032129,.01654,0.0*
1,1,.006,.032129,.01654*
20,1,.006,.032129,.01654,.032625,.010875,0.0*
1,1,.006,.032625,.010875*
20,1,.006,.032625,.010875,.032625,-.010875,0.0*
1,1,.006,.032625,-.010875*
20,1,.006,.032625,-.010875,.032129,-.01654,0.0*
1,1,.006,.032129,-.01654*
20,1,.006,.032129,-.01654,.030657,-.022033,0.0*
1,1,.006,.030657,-.022033*
20,1,.006,.030657,-.022033,.028254,-.027187,0.0*
1,1,.006,.028254,-.027187*
20,1,.006,.028254,-.027187,.024992,-.031846,0.0*
1,1,.006,.024992,-.031846*
20,1,.006,.024992,-.031846,.020971,-.035867,0.0*
1,1,.006,.020971,-.035867*
20,1,.006,.020971,-.035867,.016313,-.039129,0.0*
1,1,.006,.016313,-.039129*
20,1,.006,.016313,-.039129,.011158,-.041532,0.0*
1,1,.006,.011158,-.041532*
20,1,.006,.011158,-.041532,.005665,-.043004,0.0*
1,1,.006,.005665,-.043004*
20,1,.006,.005665,-.043004,0.0,-.0435,0.0*
1,1,.006,0.0,-.0435*
20,1,.006,0.0,-.0435,-.005665,-.043004,0.0*
1,1,.006,-.005665,-.043004*
20,1,.006,-.005665,-.043004,-.011158,-.041532,0.0*
1,1,.006,-.011158,-.041532*
20,1,.006,-.011158,-.041532,-.016312,-.039129,0.0*
1,1,.006,-.016312,-.039129*
20,1,.006,-.016312,-.039129,-.020971,-.035867,0.0*
1,1,.006,-.020971,-.035867*
20,1,.006,-.020971,-.035867,-.024992,-.031846,0.0*
1,1,.006,-.024992,-.031846*
20,1,.006,-.024992,-.031846,-.028254,-.027188,0.0*
1,1,.006,-.028254,-.027188*
20,1,.006,-.028254,-.027188,-.030657,-.022033,0.0*
1,1,.006,-.030657,-.022033*
20,1,.006,-.030657,-.022033,-.032129,-.01654,0.0*
1,1,.006,-.032129,-.01654*
20,1,.006,-.032129,-.01654,-.032625,-.010875,0.0*
1,1,.006,-.032625,-.010875*
20,1,.006,-.032625,-.010875,-.032625,.010875,0.0*
1,1,.006,-.032625,.010875*
1,1,.006,-.00924,-.01251*
20,1,.006,-.00924,-.01251,-.00544,-.01522,0.0*
1,1,.006,-.00544,-.01522*
20,1,.006,-.00544,-.01522,-.00109,-.01631,0.0*
1,1,.006,-.00109,-.01631*
20,1,.006,-.00109,-.01631,.00326,-.01522,0.0*
1,1,.006,.00326,-.01522*
20,1,.006,.00326,-.01522,.00707,-.01196,0.0*
1,1,.006,.00707,-.01196*
20,1,.006,.00707,-.01196,.00979,-.00707,0.0*
1,1,.006,.00979,-.00707*
20,1,.006,.00979,-.00707,.01087,-.00217,0.0*
1,1,.006,.01087,-.00217*
20,1,.006,.01087,-.00217,.01087,.00381,0.0*
1,1,.006,.01087,.00381*
20,1,.006,.01087,.00381,.00979,.0087,0.0*
1,1,.006,.00979,.0087*
20,1,.006,.00979,.0087,.00707,.01305,0.0*
1,1,.006,.00707,.01305*
20,1,.006,.00707,.01305,.00381,.01522,0.0*
1,1,.006,.00381,.01522*
20,1,.006,.00381,.01522,0.0,.01631,0.0*
1,1,.006,0.0,.01631*
20,1,.006,0.0,.01631,-.00435,.01522,0.0*
1,1,.006,-.00435,.01522*
20,1,.006,-.00435,.01522,-.00761,.01305,0.0*
1,1,.006,-.00761,.01305*
20,1,.006,-.00761,.01305,-.00979,.00979,0.0*
1,1,.006,-.00979,.00979*
20,1,.006,-.00979,.00979,-.01087,.00544,0.0*
1,1,.006,-.01087,.00544*
20,1,.006,-.01087,.00544,-.00979,.00163,0.0*
1,1,.006,-.00979,.00163*
20,1,.006,-.00979,.00163,-.00707,-.00217,0.0*
1,1,.006,-.00707,-.00217*
20,1,.006,-.00707,-.00217,-.00381,-.00435,0.0*
1,1,.006,-.00381,-.00435*
20,1,.006,-.00381,-.00435,0.0,-.00489,0.0*
1,1,.006,0.0,-.00489*
20,1,.006,0.0,-.00489,.00435,-.00381,0.0*
1,1,.006,.00435,-.00381*
20,1,.006,.00435,-.00381,.00761,-.00109,0.0*
1,1,.006,.00761,-.00109*
20,1,.006,.00761,-.00109,.01087,.00381,0.0*
1,1,.006,.01087,.00381*
%
%ADD14MACRO14*%
%AMMACRO11*
1,1,.006,.005,0.0*
20,1,.006,.005,0.0,-.005,0.0,0.0*
1,1,.006,-.005,0.0*
1,1,.006,0.0,.005*
20,1,.006,0.0,.005,0.0,-.005,0.0*
1,1,.006,0.0,-.005*
1,1,.006,.0025,0.0*
20,1,.006,.0025,0.0,.0025,.005,0.0*
1,1,.006,.0025,.005*
20,1,.006,.0025,.005,.0015,.004,0.0*
1,1,.006,.0015,.004*
1,1,.006,.0015,0.0*
20,1,.006,.0015,0.0,.0035,0.0,0.0*
1,1,.006,.0035,0.0*
%
%ADD11MACRO11*%
%AMMACRO16*
1,1,.006,.028995,-.07*
20,1,.006,.028995,-.07,-.028995,-.07,0.0*
1,1,.006,-.028995,-.07*
20,1,.006,-.028995,-.07,-.07,-.028995,0.0*
1,1,.006,-.07,-.028995*
20,1,.006,-.07,-.028995,-.07,.028995,0.0*
1,1,.006,-.07,.028995*
20,1,.006,-.07,.028995,-.028995,.07,0.0*
1,1,.006,-.028995,.07*
20,1,.006,-.028995,.07,.028995,.07,0.0*
1,1,.006,.028995,.07*
20,1,.006,.028995,.07,.07,.028995,0.0*
1,1,.006,.07,.028995*
20,1,.006,.07,.028995,.07,-.028995,0.0*
1,1,.006,.07,-.028995*
20,1,.006,.07,-.028995,.028995,-.07,0.0*
1,1,.006,.028995,-.07*
1,1,.006,-.02567,-.0245*
20,1,.006,-.02567,-.0245,-.01867,-.03033,0.0*
1,1,.006,-.01867,-.03033*
20,1,.006,-.01867,-.03033,-.0105,-.03383,0.0*
1,1,.006,-.0105,-.03383*
20,1,.006,-.0105,-.03383,0.0,-.035,0.0*
1,1,.006,0.0,-.035*
20,1,.006,0.0,-.035,.0105,-.03267,0.0*
1,1,.006,.0105,-.03267*
20,1,.006,.0105,-.03267,.01867,-.028,0.0*
1,1,.006,.01867,-.028*
20,1,.006,.01867,-.028,.0245,-.01983,0.0*
1,1,.006,.0245,-.01983*
20,1,.006,.0245,-.01983,.02567,-.0105,0.0*
1,1,.006,.02567,-.0105*
20,1,.006,.02567,-.0105,.02333,-.00117,0.0*
1,1,.006,.02333,-.00117*
20,1,.006,.02333,-.00117,.0175,.00467,0.0*
1,1,.006,.0175,.00467*
20,1,.006,.0175,.00467,.00933,.00933,0.0*
1,1,.006,.00933,.00933*
20,1,.006,.00933,.00933,.00117,.0105,0.0*
1,1,.006,.00117,.0105*
20,1,.006,.00117,.0105,-.007,.00933,0.0*
1,1,.006,-.007,.00933*
20,1,.006,-.007,.00933,-.0175,.00467,0.0*
1,1,.006,-.0175,.00467*
20,1,.006,-.0175,.00467,-.014,.035,0.0*
1,1,.006,-.014,.035*
20,1,.006,-.014,.035,.0175,.035,0.0*
1,1,.006,.0175,.035*
%
%ADD16MACRO16*%
%AMMACRO15*
1,1,.006,.006,.006*
20,1,.006,.006,.006,.006,-.006,0.0*
1,1,.006,.006,-.006*
20,1,.006,.006,-.006,-.006,-.006,0.0*
1,1,.006,-.006,-.006*
20,1,.006,-.006,-.006,-.006,.006,0.0*
1,1,.006,-.006,.006*
20,1,.006,-.006,.006,.006,.006,0.0*
1,1,.006,.006,.006*
1,1,.006,-.0019,.002*
20,1,.006,-.0019,.002,-.0013,.0026,0.0*
1,1,.006,-.0013,.0026*
20,1,.006,-.0013,.0026,-.0006,.0029,0.0*
1,1,.006,-.0006,.0029*
20,1,.006,-.0006,.0029,.0002,.003,0.0*
1,1,.006,.0002,.003*
20,1,.006,.0002,.003,.0012,.0028,0.0*
1,1,.006,.0012,.0028*
20,1,.006,.0012,.0028,.0019,.0023,0.0*
1,1,.006,.0019,.0023*
20,1,.006,.0019,.0023,.0021,.0017,0.0*
1,1,.006,.0021,.0017*
20,1,.006,.0021,.0017,.002,.0011,0.0*
1,1,.006,.002,.0011*
20,1,.006,.002,.0011,.0016,.0006,0.0*
1,1,.006,.0016,.0006*
20,1,.006,.0016,.0006,-.0004,-.0004,0.0*
1,1,.006,-.0004,-.0004*
20,1,.006,-.0004,-.0004,-.0013,-.0011,0.0*
1,1,.006,-.0013,-.0011*
20,1,.006,-.0013,-.0011,-.0019,-.0021,0.0*
1,1,.006,-.0019,-.0021*
20,1,.006,-.0019,-.0021,-.0021,-.003,0.0*
1,1,.006,-.0021,-.003*
20,1,.006,-.0021,-.003,.0021,-.003,0.0*
1,1,.006,.0021,-.003*
%
%ADD15MACRO15*%
%AMMACRO18*
1,1,.006,-.0215,.016*
20,1,.006,-.0215,.016,.0215,.016,0.0*
1,1,.006,.0215,.016*
20,1,.006,.0215,.016,.024278,.015757,0.0*
1,1,.006,.024278,.015757*
20,1,.006,.024278,.015757,.026972,.015035,0.0*
1,1,.006,.026972,.015035*
20,1,.006,.026972,.015035,.0295,.013856,0.0*
1,1,.006,.0295,.013856*
20,1,.006,.0295,.013856,.031785,.012257,0.0*
1,1,.006,.031785,.012257*
20,1,.006,.031785,.012257,.033757,.010285,0.0*
1,1,.006,.033757,.010285*
20,1,.006,.033757,.010285,.035356,.008,0.0*
1,1,.006,.035356,.008*
20,1,.006,.035356,.008,.036535,.005472,0.0*
1,1,.006,.036535,.005472*
20,1,.006,.036535,.005472,.037257,.002778,0.0*
1,1,.006,.037257,.002778*
20,1,.006,.037257,.002778,.0375,0.0,0.0*
1,1,.006,.0375,0.0*
20,1,.006,.0375,0.0,.037257,-.002778,0.0*
1,1,.006,.037257,-.002778*
20,1,.006,.037257,-.002778,.036535,-.005472,0.0*
1,1,.006,.036535,-.005472*
20,1,.006,.036535,-.005472,.035356,-.008,0.0*
1,1,.006,.035356,-.008*
20,1,.006,.035356,-.008,.033757,-.010285,0.0*
1,1,.006,.033757,-.010285*
20,1,.006,.033757,-.010285,.031785,-.012257,0.0*
1,1,.006,.031785,-.012257*
20,1,.006,.031785,-.012257,.0295,-.013856,0.0*
1,1,.006,.0295,-.013856*
20,1,.006,.0295,-.013856,.026972,-.015035,0.0*
1,1,.006,.026972,-.015035*
20,1,.006,.026972,-.015035,.024278,-.015757,0.0*
1,1,.006,.024278,-.015757*
20,1,.006,.024278,-.015757,.0215,-.016,0.0*
1,1,.006,.0215,-.016*
20,1,.006,.0215,-.016,-.0215,-.016,0.0*
1,1,.006,-.0215,-.016*
20,1,.006,-.0215,-.016,-.024278,-.015757,0.0*
1,1,.006,-.024278,-.015757*
20,1,.006,-.024278,-.015757,-.026972,-.015035,0.0*
1,1,.006,-.026972,-.015035*
20,1,.006,-.026972,-.015035,-.0295,-.013856,0.0*
1,1,.006,-.0295,-.013856*
20,1,.006,-.0295,-.013856,-.031785,-.012257,0.0*
1,1,.006,-.031785,-.012257*
20,1,.006,-.031785,-.012257,-.033757,-.010285,0.0*
1,1,.006,-.033757,-.010285*
20,1,.006,-.033757,-.010285,-.035356,-.008,0.0*
1,1,.006,-.035356,-.008*
20,1,.006,-.035356,-.008,-.036535,-.005472,0.0*
1,1,.006,-.036535,-.005472*
20,1,.006,-.036535,-.005472,-.037257,-.002778,0.0*
1,1,.006,-.037257,-.002778*
20,1,.006,-.037257,-.002778,-.0375,0.0,0.0*
1,1,.006,-.0375,0.0*
20,1,.006,-.0375,0.0,-.037257,.002778,0.0*
1,1,.006,-.037257,.002778*
20,1,.006,-.037257,.002778,-.036535,.005472,0.0*
1,1,.006,-.036535,.005472*
20,1,.006,-.036535,.005472,-.035356,.008,0.0*
1,1,.006,-.035356,.008*
20,1,.006,-.035356,.008,-.033757,.010285,0.0*
1,1,.006,-.033757,.010285*
20,1,.006,-.033757,.010285,-.031785,.012257,0.0*
1,1,.006,-.031785,.012257*
20,1,.006,-.031785,.012257,-.0295,.013856,0.0*
1,1,.006,-.0295,.013856*
20,1,.006,-.0295,.013856,-.026972,.015035,0.0*
1,1,.006,-.026972,.015035*
20,1,.006,-.026972,.015035,-.024278,.015757,0.0*
1,1,.006,-.024278,.015757*
20,1,.006,-.024278,.015757,-.0215,.016,0.0*
1,1,.006,-.0215,.016*
1,1,.006,-.008,-.008*
20,1,.006,-.008,-.008,-.008,.008,0.0*
1,1,.006,-.008,.008*
20,1,.006,-.008,.008,-.0112,.0048,0.0*
1,1,.006,-.0112,.0048*
1,1,.006,-.0112,-.008*
20,1,.006,-.0112,-.008,-.0048,-.008,0.0*
1,1,.006,-.0048,-.008*
1,1,.006,.00801,-.008*
20,1,.006,.00801,-.008,.00801,.008,0.0*
1,1,.006,.00801,.008*
20,1,.006,.00801,.008,.00481,.0048,0.0*
1,1,.006,.00481,.0048*
1,1,.006,.00481,-.008*
20,1,.006,.00481,-.008,.01121,-.008,0.0*
1,1,.006,.01121,-.008*
%
%ADD18MACRO18*%
%AMMACRO12*
1,1,.006,.0005,0.0*
20,1,.006,.0005,0.0,0.0,-.0005,0.0*
1,1,.006,0.0,-.0005*
20,1,.006,0.0,-.0005,-.0005,0.0,0.0*
1,1,.006,-.0005,0.0*
20,1,.006,-.0005,0.0,0.0,.0005,0.0*
1,1,.006,0.0,.0005*
20,1,.006,0.0,.0005,.0005,0.0,0.0*
1,1,.006,.0005,0.0*
1,1,.006,-.00016,-.00004*
20,1,.006,-.00016,-.00004,-.0001,.00002,0.0*
1,1,.006,-.0001,.00002*
20,1,.006,-.0001,.00002,-.00005,.00005,0.0*
1,1,.006,-.00005,.00005*
20,1,.006,-.00005,.00005,.00002,.00007,0.0*
1,1,.006,.00002,.00007*
20,1,.006,.00002,.00007,.00008,.00005,0.0*
1,1,.006,.00008,.00005*
20,1,.006,.00008,.00005,.00012,.00002,0.0*
1,1,.006,.00012,.00002*
20,1,.006,.00012,.00002,.00015,-.00003,0.0*
1,1,.006,.00015,-.00003*
20,1,.006,.00015,-.00003,.00016,-.00009,0.0*
1,1,.006,.00016,-.00009*
20,1,.006,.00016,-.00009,.00015,-.00014,0.0*
1,1,.006,.00015,-.00014*
20,1,.006,.00015,-.00014,.00012,-.00019,0.0*
1,1,.006,.00012,-.00019*
20,1,.006,.00012,-.00019,.00007,-.00023,0.0*
1,1,.006,.00007,-.00023*
20,1,.006,.00007,-.00023,.00001,-.00025,0.0*
1,1,.006,.00001,-.00025*
20,1,.006,.00001,-.00025,-.00006,-.00023,0.0*
1,1,.006,-.00006,-.00023*
20,1,.006,-.00006,-.00023,-.00012,-.00018,0.0*
1,1,.006,-.00012,-.00018*
20,1,.006,-.00012,-.00018,-.00015,-.00011,0.0*
1,1,.006,-.00015,-.00011*
20,1,.006,-.00015,-.00011,-.00016,-.00003,0.0*
1,1,.006,-.00016,-.00003*
20,1,.006,-.00016,-.00003,-.00014,.00008,0.0*
1,1,.006,-.00014,.00008*
20,1,.006,-.00014,.00008,-.00012,.00014,0.0*
1,1,.006,-.00012,.00014*
20,1,.006,-.00012,.00014,-.00008,.0002,0.0*
1,1,.006,-.00008,.0002*
20,1,.006,-.00008,.0002,-.00002,.00024,0.0*
1,1,.006,-.00002,.00024*
20,1,.006,-.00002,.00024,.00004,.00025,0.0*
1,1,.006,.00004,.00025*
20,1,.006,.00004,.00025,.0001,.00023,0.0*
1,1,.006,.0001,.00023*
20,1,.006,.0001,.00023,.00014,.00019,0.0*
1,1,.006,.00014,.00019*
%
%ADD12MACRO12*%
%AMMACRO13*
1,1,.006,0.0,.01*
20,1,.006,0.0,.01,-.00866,.005,0.0*
1,1,.006,-.00866,.005*
20,1,.006,-.00866,.005,-.00866,-.005,0.0*
1,1,.006,-.00866,-.005*
20,1,.006,-.00866,-.005,0.0,-.01,0.0*
1,1,.006,0.0,-.01*
20,1,.006,0.0,-.01,.00866,-.005,0.0*
1,1,.006,.00866,-.005*
20,1,.006,.00866,-.005,.00866,.005,0.0*
1,1,.006,.00866,.005*
20,1,.006,.00866,.005,0.0,.01,0.0*
1,1,.006,0.0,.01*
1,1,.006,.002,-.005*
20,1,.006,.002,-.005,.002,.005,0.0*
1,1,.006,.002,.005*
20,1,.006,.002,.005,-.00417,-.00217,0.0*
1,1,.006,-.00417,-.00217*
20,1,.006,-.00417,-.00217,.00417,-.00217,0.0*
1,1,.006,.00417,-.00217*
%
%ADD13MACRO13*%
%AMMACRO17*
1,1,.006,.008,0.0*
20,1,.006,.008,0.0,.004,.006928,0.0*
1,1,.006,.004,.006928*
20,1,.006,.004,.006928,-.004,.006928,0.0*
1,1,.006,-.004,.006928*
20,1,.006,-.004,.006928,-.008,0.0,0.0*
1,1,.006,-.008,0.0*
20,1,.006,-.008,0.0,-.004,-.006928,0.0*
1,1,.006,-.004,-.006928*
20,1,.006,-.004,-.006928,.004,-.006928,0.0*
1,1,.006,.004,-.006928*
20,1,.006,.004,-.006928,.008,0.0,0.0*
1,1,.006,.008,0.0*
1,1,.006,-.00293,-.0024*
20,1,.006,-.00293,-.0024,-.00213,-.00333,0.0*
1,1,.006,-.00213,-.00333*
20,1,.006,-.00213,-.00333,-.00107,-.00387,0.0*
1,1,.006,-.00107,-.00387*
20,1,.006,-.00107,-.00387,.00013,-.004,0.0*
1,1,.006,.00013,-.004*
20,1,.006,.00013,-.004,.0012,-.00387,0.0*
1,1,.006,.0012,-.00387*
20,1,.006,.0012,-.00387,.00227,-.0032,0.0*
1,1,.006,.00227,-.0032*
20,1,.006,.00227,-.0032,.00293,-.0024,0.0*
1,1,.006,.00293,-.0024*
20,1,.006,.00293,-.0024,.00307,-.0016,0.0*
1,1,.006,.00307,-.0016*
20,1,.006,.00307,-.0016,.0028,-.00067,0.0*
1,1,.006,.0028,-.00067*
20,1,.006,.0028,-.00067,.00187,0.0,0.0*
1,1,.006,.00187,0.0*
20,1,.006,.00187,0.0,.00093,.00027,0.0*
1,1,.006,.00093,.00027*
20,1,.006,.00093,.00027,-.00027,.00027,0.0*
1,1,.006,-.00027,.00027*
1,1,.006,.00093,.00027*
20,1,.006,.00093,.00027,.00173,.00067,0.0*
1,1,.006,.00173,.00067*
20,1,.006,.00173,.00067,.0024,.00133,0.0*
1,1,.006,.0024,.00133*
20,1,.006,.0024,.00133,.00267,.00213,0.0*
1,1,.006,.00267,.00213*
20,1,.006,.00267,.00213,.0024,.00293,0.0*
1,1,.006,.0024,.00293*
20,1,.006,.0024,.00293,.00173,.0036,0.0*
1,1,.006,.00173,.0036*
20,1,.006,.00173,.0036,.00053,.004,0.0*
1,1,.006,.00053,.004*
20,1,.006,.00053,.004,-.00067,.00387,0.0*
1,1,.006,-.00067,.00387*
20,1,.006,-.00067,.00387,-.00187,.00333,0.0*
1,1,.006,-.00187,.00333*
%
%ADD17MACRO17*%
%AMMACRO20*
1,1,.006,.073,.05475*
20,1,.006,.073,.05475,.073,-.05475,0.0*
1,1,.006,.073,-.05475*
20,1,.006,.073,-.05475,-.073,-.05475,0.0*
1,1,.006,-.073,-.05475*
20,1,.006,-.073,-.05475,-.073,.05475,0.0*
1,1,.006,-.073,.05475*
20,1,.006,-.073,.05475,.073,.05475,0.0*
1,1,.006,.073,.05475*
1,1,.006,-.02738,-.02737*
20,1,.006,-.02738,-.02737,-.02738,.02738,0.0*
1,1,.006,-.02738,.02738*
20,1,.006,-.02738,.02738,-.03833,.01643,0.0*
1,1,.006,-.03833,.01643*
1,1,.006,-.03833,-.02737*
20,1,.006,-.03833,-.02737,-.01643,-.02737,0.0*
1,1,.006,-.01643,-.02737*
1,1,.006,.02738,.02738*
20,1,.006,.02738,.02738,.02008,.02556,0.0*
1,1,.006,.02008,.02556*
20,1,.006,.02008,.02556,.01461,.02099,0.0*
1,1,.006,.01461,.02099*
20,1,.006,.01461,.02099,.01096,.01552,0.0*
1,1,.006,.01096,.01552*
20,1,.006,.01096,.01552,.00822,.00822,0.0*
1,1,.006,.00822,.00822*
20,1,.006,.00822,.00822,.00731,0.0,0.0*
1,1,.006,.00731,0.0*
20,1,.006,.00731,0.0,.00822,-.00821,0.0*
1,1,.006,.00822,-.00821*
20,1,.006,.00822,-.00821,.01096,-.01551,0.0*
1,1,.006,.01096,-.01551*
20,1,.006,.01096,-.01551,.01461,-.02098,0.0*
1,1,.006,.01461,-.02098*
20,1,.006,.01461,-.02098,.02008,-.02555,0.0*
1,1,.006,.02008,-.02555*
20,1,.006,.02008,-.02555,.02738,-.02737,0.0*
1,1,.006,.02738,-.02737*
20,1,.006,.02738,-.02737,.03468,-.02555,0.0*
1,1,.006,.03468,-.02555*
20,1,.006,.03468,-.02555,.04016,-.02098,0.0*
1,1,.006,.04016,-.02098*
20,1,.006,.04016,-.02098,.04381,-.01551,0.0*
1,1,.006,.04381,-.01551*
20,1,.006,.04381,-.01551,.04655,-.00821,0.0*
1,1,.006,.04655,-.00821*
20,1,.006,.04655,-.00821,.04746,0.0,0.0*
1,1,.006,.04746,0.0*
20,1,.006,.04746,0.0,.04655,.00822,0.0*
1,1,.006,.04655,.00822*
20,1,.006,.04655,.00822,.04381,.01552,0.0*
1,1,.006,.04381,.01552*
20,1,.006,.04381,.01552,.04016,.02099,0.0*
1,1,.006,.04016,.02099*
20,1,.006,.04016,.02099,.03468,.02556,0.0*
1,1,.006,.03468,.02556*
20,1,.006,.03468,.02556,.02738,.02738,0.0*
1,1,.006,.02738,.02738*
%
%ADD20MACRO20*%
%AMMACRO19*
1,1,.006,0.0,.0365*
20,1,.006,0.0,.0365,.0365,-.0365,0.0*
1,1,.006,.0365,-.0365*
20,1,.006,.0365,-.0365,-.0365,-.0365,0.0*
1,1,.006,-.0365,-.0365*
20,1,.006,-.0365,-.0365,0.0,.0365,0.0*
1,1,.006,0.0,.0365*
1,1,.006,-.00122,-.01825*
20,1,.006,-.00122,-.01825,0.0,-.01034,0.0*
1,1,.006,0.0,-.01034*
20,1,.006,0.0,-.01034,.00183,-.00365,0.0*
1,1,.006,.00183,-.00365*
20,1,.006,.00183,-.00365,.00426,.00243,0.0*
1,1,.006,.00426,.00243*
20,1,.006,.00426,.00243,.0073,.00912,0.0*
1,1,.006,.0073,.00912*
20,1,.006,.0073,.00912,.01217,.01825,0.0*
1,1,.006,.01217,.01825*
20,1,.006,.01217,.01825,-.01217,.01825,0.0*
1,1,.006,-.01217,.01825*
%
%ADD19MACRO19*%
%AMMACRO10*
1,1,.006,-.01075,.03225*
20,1,.006,-.01075,.03225,.01075,.03225,0.0*
1,1,.006,.01075,.03225*
20,1,.006,.01075,.03225,.01635,.03176,0.0*
1,1,.006,.01635,.03176*
20,1,.006,.01635,.03176,.02178,.030305,0.0*
1,1,.006,.02178,.030305*
20,1,.006,.02178,.030305,.026875,.027929,0.0*
1,1,.006,.026875,.027929*
20,1,.006,.026875,.027929,.03148,.024705,0.0*
1,1,.006,.03148,.024705*
20,1,.006,.03148,.024705,.035455,.02073,0.0*
1,1,.006,.035455,.02073*
20,1,.006,.035455,.02073,.038679,.016125,0.0*
1,1,.006,.038679,.016125*
20,1,.006,.038679,.016125,.041055,.01103,0.0*
1,1,.006,.041055,.01103*
20,1,.006,.041055,.01103,.04251,.0056,0.0*
1,1,.006,.04251,.0056*
20,1,.006,.04251,.0056,.043,0.0,0.0*
1,1,.006,.043,0.0*
20,1,.006,.043,0.0,.04251,-.0056,0.0*
1,1,.006,.04251,-.0056*
20,1,.006,.04251,-.0056,.041055,-.01103,0.0*
1,1,.006,.041055,-.01103*
20,1,.006,.041055,-.01103,.038679,-.016125,0.0*
1,1,.006,.038679,-.016125*
20,1,.006,.038679,-.016125,.035455,-.02073,0.0*
1,1,.006,.035455,-.02073*
20,1,.006,.035455,-.02073,.03148,-.024705,0.0*
1,1,.006,.03148,-.024705*
20,1,.006,.03148,-.024705,.026875,-.027929,0.0*
1,1,.006,.026875,-.027929*
20,1,.006,.026875,-.027929,.02178,-.030305,0.0*
1,1,.006,.02178,-.030305*
20,1,.006,.02178,-.030305,.01635,-.03176,0.0*
1,1,.006,.01635,-.03176*
20,1,.006,.01635,-.03176,.01075,-.03225,0.0*
1,1,.006,.01075,-.03225*
20,1,.006,.01075,-.03225,-.01075,-.03225,0.0*
1,1,.006,-.01075,-.03225*
20,1,.006,-.01075,-.03225,-.01635,-.03176,0.0*
1,1,.006,-.01635,-.03176*
20,1,.006,-.01635,-.03176,-.02178,-.030305,0.0*
1,1,.006,-.02178,-.030305*
20,1,.006,-.02178,-.030305,-.026875,-.027929,0.0*
1,1,.006,-.026875,-.027929*
20,1,.006,-.026875,-.027929,-.03148,-.024705,0.0*
1,1,.006,-.03148,-.024705*
20,1,.006,-.03148,-.024705,-.035455,-.02073,0.0*
1,1,.006,-.035455,-.02073*
20,1,.006,-.035455,-.02073,-.038679,-.016125,0.0*
1,1,.006,-.038679,-.016125*
20,1,.006,-.038679,-.016125,-.041055,-.01103,0.0*
1,1,.006,-.041055,-.01103*
20,1,.006,-.041055,-.01103,-.04251,-.0056,0.0*
1,1,.006,-.04251,-.0056*
20,1,.006,-.04251,-.0056,-.043,0.0,0.0*
1,1,.006,-.043,0.0*
20,1,.006,-.043,0.0,-.04251,.0056,0.0*
1,1,.006,-.04251,.0056*
20,1,.006,-.04251,.0056,-.041055,.01103,0.0*
1,1,.006,-.041055,.01103*
20,1,.006,-.041055,.01103,-.038679,.016125,0.0*
1,1,.006,-.038679,.016125*
20,1,.006,-.038679,.016125,-.035455,.02073,0.0*
1,1,.006,-.035455,.02073*
20,1,.006,-.035455,.02073,-.03148,.024705,0.0*
1,1,.006,-.03148,.024705*
20,1,.006,-.03148,.024705,-.026875,.027929,0.0*
1,1,.006,-.026875,.027929*
20,1,.006,-.026875,.027929,-.02178,.030305,0.0*
1,1,.006,-.02178,.030305*
20,1,.006,-.02178,.030305,-.01635,.03176,0.0*
1,1,.006,-.01635,.03176*
20,1,.006,-.01635,.03176,-.01075,.03225,0.0*
1,1,.006,-.01075,.03225*
1,1,.006,0.0,-.01612*
20,1,.006,0.0,-.01612,.00377,-.01558,0.0*
1,1,.006,.00377,-.01558*
20,1,.006,.00377,-.01558,.00807,-.01397,0.0*
1,1,.006,.00807,-.01397*
20,1,.006,.00807,-.01397,.01076,-.01128,0.0*
1,1,.006,.01076,-.01128*
20,1,.006,.01076,-.01128,.01183,-.00752,0.0*
1,1,.006,.01183,-.00752*
20,1,.006,.01183,-.00752,.01076,-.00376,0.0*
1,1,.006,.01076,-.00376*
20,1,.006,.01076,-.00376,.00753,-.00053,0.0*
1,1,.006,.00753,-.00053*
20,1,.006,.00753,-.00053,.00269,.00108,0.0*
1,1,.006,.00269,.00108*
20,1,.006,.00269,.00108,-.00268,.00108,0.0*
1,1,.006,-.00268,.00108*
20,1,.006,-.00268,.00108,-.00591,.00216,0.0*
1,1,.006,-.00591,.00216*
20,1,.006,-.00591,.00216,-.0086,.00484,0.0*
1,1,.006,-.0086,.00484*
20,1,.006,-.0086,.00484,-.00967,.0086,0.0*
1,1,.006,-.00967,.0086*
20,1,.006,-.00967,.0086,-.00806,.01237,0.0*
1,1,.006,-.00806,.01237*
20,1,.006,-.00806,.01237,-.0043,.01506,0.0*
1,1,.006,-.0043,.01506*
20,1,.006,-.0043,.01506,0.0,.01613,0.0*
1,1,.006,0.0,.01613*
20,1,.006,0.0,.01613,.0043,.01506,0.0*
1,1,.006,.0043,.01506*
20,1,.006,.0043,.01506,.00807,.01237,0.0*
1,1,.006,.00807,.01237*
20,1,.006,.00807,.01237,.00968,.0086,0.0*
1,1,.006,.00968,.0086*
20,1,.006,.00968,.0086,.0086,.00484,0.0*
1,1,.006,.0086,.00484*
20,1,.006,.0086,.00484,.00592,.00216,0.0*
1,1,.006,.00592,.00216*
20,1,.006,.00592,.00216,.00269,.00108,0.0*
1,1,.006,.00269,.00108*
20,1,.006,.00269,.00108,-.00268,.00108,0.0*
1,1,.006,-.00268,.00108*
20,1,.006,-.00268,.00108,-.00752,-.00053,0.0*
1,1,.006,-.00752,-.00053*
20,1,.006,-.00752,-.00053,-.01075,-.00376,0.0*
1,1,.006,-.01075,-.00376*
20,1,.006,-.01075,-.00376,-.01182,-.00752,0.0*
1,1,.006,-.01182,-.00752*
20,1,.006,-.01182,-.00752,-.01075,-.01128,0.0*
1,1,.006,-.01075,-.01128*
20,1,.006,-.01075,-.01128,-.00806,-.01397,0.0*
1,1,.006,-.00806,-.01397*
20,1,.006,-.00806,-.01397,-.00376,-.01558,0.0*
1,1,.006,-.00376,-.01558*
20,1,.006,-.00376,-.01558,0.0,-.01612,0.0*
1,1,.006,0.0,-.01612*
%
%ADD10MACRO10*%
%ADD21C,.02*%
%ADD22C,.006*%
G75*
%LPD*%
G75*
G54D10*
X-63741Y15000D03*
X-42339Y1008909D03*
X-63741Y1977126D03*
X25499Y1950499D03*
X1010999Y43999D03*
X1010499Y1950499D03*
X1101142Y15000D03*
Y1977126D03*
X1271996Y220679D03*
G54D20*
X1023228Y1416024D03*
Y1694212D03*
X1271996Y164479D03*
G54D11*
X20000Y40000D03*
Y20000D03*
X5500Y40982D03*
Y20982D03*
X10018Y5500D03*
X30018D03*
X20000Y80000D03*
Y100000D03*
Y120000D03*
Y60000D03*
X5500Y120982D03*
Y100982D03*
Y80982D03*
Y60982D03*
X20000Y160000D03*
Y180000D03*
Y140000D03*
X5500Y180982D03*
Y160982D03*
Y140982D03*
X20000Y240000D03*
Y200000D03*
Y220000D03*
X5500Y260982D03*
Y240982D03*
Y220982D03*
Y200982D03*
Y320982D03*
Y300982D03*
Y280982D03*
X27500Y380000D03*
X20000D03*
Y400000D03*
X5500Y400982D03*
Y380982D03*
Y360982D03*
Y340982D03*
X20000Y340000D03*
X27000Y440000D03*
X20000Y460000D03*
Y440000D03*
Y480000D03*
Y420000D03*
X5500Y480982D03*
Y460982D03*
Y440982D03*
Y420982D03*
X27500Y540000D03*
Y553500D03*
X20000Y540000D03*
Y500000D03*
Y520000D03*
X5500Y540982D03*
Y520982D03*
Y500982D03*
X24500Y624897D03*
Y612249D03*
Y619093D03*
Y606544D03*
Y599700D03*
X16500Y624765D03*
Y618765D03*
Y612166D03*
Y606166D03*
Y598197D03*
X20000Y607620D03*
Y610820D03*
Y620218D03*
Y623418D03*
X27529Y601522D03*
Y604722D03*
Y614071D03*
Y617271D03*
Y626719D03*
Y629919D03*
X24500Y700488D03*
Y694733D03*
Y687889D03*
Y675291D03*
Y682135D03*
Y669537D03*
Y662693D03*
Y637496D03*
Y644340D03*
Y631741D03*
X16500Y700355D03*
Y694355D03*
Y687757D03*
Y681757D03*
Y675158D03*
Y669158D03*
Y662226D03*
Y657000D03*
Y649500D03*
Y644530D03*
Y637363D03*
Y631363D03*
X20000Y658013D03*
Y661213D03*
Y670612D03*
Y673812D03*
Y683210D03*
Y686410D03*
Y632817D03*
Y636017D03*
Y695809D03*
Y699009D03*
Y645415D03*
Y648615D03*
X27529Y664515D03*
Y667715D03*
Y677113D03*
Y680313D03*
Y689711D03*
Y692911D03*
Y702310D03*
Y639318D03*
Y642518D03*
X24500Y769579D03*
Y763825D03*
Y756981D03*
Y725485D03*
Y732329D03*
Y719730D03*
Y712886D03*
Y707332D03*
X16500Y769646D03*
Y763646D03*
Y757048D03*
Y725552D03*
Y719552D03*
Y712953D03*
Y706953D03*
Y751658D03*
Y732500D03*
X20000Y708407D03*
Y711607D03*
Y721006D03*
Y724206D03*
Y752502D03*
Y755702D03*
Y765100D03*
Y768300D03*
X27529Y714708D03*
Y717908D03*
Y727307D03*
Y730507D03*
Y758803D03*
Y762003D03*
Y705510D03*
Y771401D03*
Y774601D03*
X27699Y737535D03*
X24500Y848664D03*
Y841820D03*
Y836266D03*
Y829422D03*
Y816823D03*
Y823667D03*
Y804225D03*
Y811069D03*
Y798470D03*
Y791626D03*
Y776423D03*
X16500Y848686D03*
Y842087D03*
Y836087D03*
Y829489D03*
Y823489D03*
Y816891D03*
Y810891D03*
Y804292D03*
Y798292D03*
Y791694D03*
Y785694D03*
Y777725D03*
X20000Y837541D03*
Y840741D03*
Y787147D03*
Y790347D03*
Y799746D03*
Y802946D03*
Y812344D03*
Y815544D03*
Y824943D03*
Y828143D03*
X27529Y843642D03*
Y846842D03*
Y793448D03*
Y796648D03*
Y806047D03*
Y809247D03*
Y818645D03*
Y821845D03*
Y831244D03*
Y834444D03*
X24500Y911856D03*
Y905012D03*
Y892414D03*
Y899258D03*
Y886509D03*
Y879665D03*
Y867017D03*
Y873861D03*
Y854419D03*
Y861263D03*
X16500Y917678D03*
Y911678D03*
Y905079D03*
Y899079D03*
Y879883D03*
Y873883D03*
Y867284D03*
Y861284D03*
Y854686D03*
Y889500D03*
X20000Y900533D03*
Y903733D03*
Y850139D03*
Y853339D03*
Y913132D03*
Y916332D03*
Y862738D03*
Y865938D03*
Y875336D03*
Y878536D03*
X27529Y894236D03*
Y897436D03*
Y856241D03*
Y859441D03*
Y906834D03*
Y910034D03*
Y868839D03*
Y872039D03*
Y881487D03*
Y884687D03*
X34872Y890906D03*
X36000Y960000D03*
X20000Y980000D03*
Y960000D03*
Y940000D03*
X16000Y931000D03*
X34500Y925000D03*
X5500Y980299D03*
X30000Y991000D03*
X36500Y999500D03*
X5500Y1040299D03*
Y1020299D03*
Y1000299D03*
X23291Y1062791D03*
X24500Y1133365D03*
Y1102601D03*
Y1095769D03*
Y1108368D03*
Y1115200D03*
X16500Y1140024D03*
Y1120828D03*
Y1114828D03*
Y1108229D03*
Y1102229D03*
Y1133500D03*
Y1094260D03*
X31707Y1086000D03*
X20000Y1103683D03*
Y1106883D03*
Y1116281D03*
Y1119481D03*
X27529Y1135181D03*
Y1138381D03*
Y1097585D03*
Y1100785D03*
Y1110184D03*
Y1113384D03*
X32335Y1122002D03*
X37396Y1130912D03*
X33971Y1131741D03*
X24500Y1208955D03*
Y1196357D03*
Y1203189D03*
Y1183758D03*
Y1190590D03*
Y1171160D03*
Y1177992D03*
Y1165394D03*
Y1158562D03*
Y1152795D03*
Y1145963D03*
Y1140197D03*
X16500Y1209016D03*
Y1203016D03*
Y1196418D03*
Y1190418D03*
Y1183820D03*
Y1177820D03*
Y1171221D03*
Y1165221D03*
Y1158623D03*
Y1152623D03*
Y1146024D03*
X20000Y1141478D03*
Y1144678D03*
Y1191872D03*
Y1195072D03*
Y1154076D03*
Y1157276D03*
Y1204470D03*
Y1207670D03*
Y1166675D03*
Y1169875D03*
Y1179273D03*
Y1182473D03*
X27529Y1185574D03*
Y1188774D03*
Y1147779D03*
Y1150979D03*
Y1198173D03*
Y1201373D03*
Y1160378D03*
Y1163578D03*
Y1210771D03*
Y1172976D03*
Y1176176D03*
X24500Y1285079D03*
Y1278247D03*
Y1272480D03*
Y1265648D03*
Y1259882D03*
Y1253050D03*
Y1228386D03*
Y1221554D03*
Y1215787D03*
X16500Y1284906D03*
Y1278308D03*
Y1272308D03*
Y1265709D03*
Y1259709D03*
Y1253111D03*
Y1247721D03*
Y1221615D03*
Y1215615D03*
Y1228500D03*
X20000Y1261163D03*
Y1264363D03*
Y1273761D03*
Y1276961D03*
Y1217069D03*
Y1220269D03*
Y1248565D03*
Y1251765D03*
X27529Y1254866D03*
Y1258066D03*
Y1267464D03*
Y1270664D03*
Y1280063D03*
Y1283263D03*
Y1213971D03*
Y1223370D03*
Y1226570D03*
X33201Y1230674D03*
X32959Y1234478D03*
X36000Y1236000D03*
X24500Y1357720D03*
Y1350888D03*
Y1345121D03*
Y1338289D03*
Y1332523D03*
Y1325691D03*
Y1319924D03*
Y1313092D03*
Y1290845D03*
Y1297677D03*
X34000Y1321000D03*
X16500Y1357347D03*
Y1350749D03*
Y1344749D03*
Y1338150D03*
Y1332150D03*
Y1325552D03*
Y1319552D03*
Y1303505D03*
Y1297505D03*
Y1290906D03*
X16417Y1311583D03*
X20000Y1321006D03*
Y1324206D03*
Y1333604D03*
Y1336804D03*
Y1346202D03*
Y1349402D03*
Y1286360D03*
Y1289560D03*
Y1298958D03*
Y1302158D03*
X27529Y1314908D03*
Y1318108D03*
Y1327507D03*
Y1330707D03*
Y1340105D03*
Y1343305D03*
Y1352704D03*
Y1355904D03*
Y1292661D03*
Y1295861D03*
X36170Y1308434D03*
X33699Y1301782D03*
X26500Y1305121D03*
X33938Y1311000D03*
X38500D03*
X30000Y1305000D03*
X30700Y1308600D03*
X24500Y1401081D03*
Y1407913D03*
Y1388483D03*
Y1395315D03*
Y1375884D03*
Y1382716D03*
Y1370118D03*
Y1363286D03*
X21000Y1424500D03*
X16500Y1413741D03*
Y1407741D03*
Y1401142D03*
Y1395142D03*
Y1388544D03*
Y1382544D03*
Y1375946D03*
Y1369946D03*
Y1363347D03*
X20000Y1371399D03*
Y1374599D03*
Y1383998D03*
Y1387198D03*
Y1396596D03*
Y1399796D03*
Y1358801D03*
Y1362001D03*
Y1409195D03*
Y1412395D03*
X27529Y1365102D03*
Y1368302D03*
Y1377700D03*
Y1380900D03*
Y1390299D03*
Y1393499D03*
Y1402897D03*
Y1406097D03*
X27000Y1417500D03*
X32500Y1417600D03*
X22000Y1487000D03*
X37000Y1443500D03*
X30500Y1463500D03*
X28000Y1444000D03*
X36401Y1521623D03*
X32801D03*
X24500Y1560197D03*
Y1566907D03*
Y1547598D03*
Y1554308D03*
Y1522401D03*
Y1529111D03*
Y1541710D03*
Y1535000D03*
X16500Y1573000D03*
Y1566500D03*
Y1560500D03*
Y1554000D03*
Y1548000D03*
Y1541500D03*
Y1535000D03*
Y1529000D03*
Y1521031D03*
Y1512500D03*
X20000Y1530454D03*
Y1533654D03*
Y1543052D03*
Y1546252D03*
Y1555650D03*
Y1558850D03*
Y1568249D03*
Y1571449D03*
X27529Y1524156D03*
Y1527356D03*
Y1536755D03*
Y1539955D03*
Y1549353D03*
Y1552553D03*
Y1561952D03*
Y1565152D03*
X33001Y1518123D03*
X36201D03*
X24500Y1632638D03*
Y1639348D03*
Y1626749D03*
Y1620039D03*
Y1614151D03*
Y1607441D03*
Y1601552D03*
Y1594842D03*
Y1588954D03*
Y1582244D03*
X16500Y1644735D03*
Y1639845D03*
Y1633000D03*
Y1626500D03*
Y1620000D03*
Y1614000D03*
Y1607500D03*
Y1601500D03*
Y1595000D03*
Y1588500D03*
Y1582500D03*
X20000Y1640690D03*
Y1643890D03*
Y1593496D03*
Y1590296D03*
Y1606094D03*
Y1602894D03*
Y1618693D03*
Y1615493D03*
Y1631291D03*
Y1628091D03*
X27529Y1634393D03*
Y1637593D03*
Y1587199D03*
Y1583999D03*
Y1599797D03*
Y1596597D03*
Y1612396D03*
Y1609196D03*
Y1624994D03*
Y1621794D03*
X24500Y1717868D03*
Y1702531D03*
Y1695821D03*
Y1689932D03*
Y1683222D03*
Y1677334D03*
Y1670624D03*
X16500Y1669933D03*
Y1677000D03*
Y1683170D03*
Y1689500D03*
Y1696000D03*
Y1702500D03*
Y1712000D03*
Y1717462D03*
Y1665044D03*
X20000Y1716331D03*
Y1713131D03*
Y1665887D03*
Y1669087D03*
Y1678485D03*
Y1681685D03*
Y1691083D03*
Y1694283D03*
X27529Y1719623D03*
Y1672379D03*
Y1675579D03*
Y1684977D03*
Y1688177D03*
Y1697576D03*
Y1700776D03*
X35900Y1706000D03*
X34224Y1709000D03*
X38000Y1715000D03*
X31981Y1768323D03*
X24500Y1755663D03*
Y1762373D03*
Y1743065D03*
Y1749775D03*
Y1730466D03*
Y1737176D03*
Y1724578D03*
X22219Y1768323D03*
X16500Y1749000D03*
Y1756052D03*
Y1765000D03*
Y1774500D03*
Y1784000D03*
Y1790500D03*
Y1724000D03*
Y1730658D03*
Y1736500D03*
Y1743356D03*
X20000Y1728929D03*
Y1725729D03*
Y1741528D03*
Y1738328D03*
Y1754126D03*
Y1750926D03*
X27529Y1722823D03*
Y1735421D03*
Y1732221D03*
Y1748020D03*
Y1744820D03*
Y1760618D03*
Y1757418D03*
X25500Y1769558D03*
X28700D03*
X39500Y1823300D03*
X39400Y1819900D03*
X38400Y1846750D03*
X38300Y1859050D03*
X5500Y1880685D03*
Y1888685D03*
X38500Y1871350D03*
X38200Y1883800D03*
X19974Y1943969D03*
X33700Y1960300D03*
X20000Y1960000D03*
Y1980000D03*
X32559Y1986626D03*
X12559D03*
X5500Y1973685D03*
Y1953685D03*
X30200Y1970300D03*
X40000Y40000D03*
Y20000D03*
X90018Y5500D03*
X110018D03*
X50018D03*
X70018D03*
X109038Y62310D03*
X109000Y81106D03*
X109160Y105900D03*
X60000Y80000D03*
X40000D03*
Y100000D03*
Y120000D03*
Y60000D03*
X109038Y68476D03*
X109000Y87476D03*
X109160Y100476D03*
X96000Y114212D03*
Y107913D03*
Y98464D03*
Y89015D03*
Y79567D03*
Y70118D03*
Y60868D03*
X96100Y52300D03*
X72500Y91161D03*
Y86161D03*
X71000Y58000D03*
X96000Y119000D03*
X99500Y95940D03*
Y91540D03*
Y77042D03*
Y72642D03*
Y58244D03*
Y53844D03*
X105000Y104788D03*
Y101588D03*
Y85891D03*
Y82691D03*
Y66993D03*
Y63793D03*
X72500Y61161D03*
X67500Y124088D03*
X108917Y150188D03*
X100000Y180000D03*
X99800Y194200D03*
X40000Y160000D03*
Y180000D03*
Y140000D03*
X67500Y135830D03*
X108917Y156976D03*
X72500Y166161D03*
X96000Y158307D03*
X72500Y151161D03*
X96000Y148858D03*
X72500Y136161D03*
X96000Y139409D03*
Y134000D03*
Y123661D03*
X104000Y125000D03*
X71000Y125236D03*
X68000Y128359D03*
Y131559D03*
X99500Y146333D03*
Y141933D03*
X105000Y155182D03*
Y151982D03*
X85250Y247238D03*
X80000Y200000D03*
X77306Y259381D03*
X40000Y240000D03*
Y200000D03*
Y220000D03*
X99300Y201000D03*
X60306Y212338D03*
X80153Y230246D03*
X85427Y239715D03*
X100400Y208300D03*
X70500Y242988D03*
X80300Y234465D03*
X97400Y220200D03*
X97000Y296500D03*
X111500Y276000D03*
X84500Y315000D03*
X67000Y269000D03*
X66512Y287899D03*
X66610Y295956D03*
X56024Y292549D03*
X97400Y366600D03*
X95849Y361564D03*
X46487Y360400D03*
X48822Y393916D03*
X100400Y406000D03*
X104400D03*
X107900D03*
X96900D03*
X110000Y362500D03*
X106500D03*
X110000Y366000D03*
X106500D03*
X92700Y358400D03*
X52066Y370649D03*
X109044Y467822D03*
X51500Y469000D03*
X112600Y442500D03*
X98300Y443400D03*
X109044Y473988D03*
X96000Y485079D03*
Y475630D03*
Y466181D03*
Y456732D03*
X71000Y463500D03*
X112600Y439000D03*
X99500Y482554D03*
Y478154D03*
Y463656D03*
Y459256D03*
X105000Y472505D03*
Y469305D03*
X72500Y466673D03*
X109000Y486618D03*
X109138Y505912D03*
X67500Y529600D03*
X108917Y555700D03*
X67500Y541342D03*
X109000Y492988D03*
X109138Y511488D03*
X72500Y556673D03*
X96000Y554369D03*
X72500Y541673D03*
X96000Y544921D03*
Y539500D03*
Y529173D03*
Y519724D03*
Y513425D03*
Y503976D03*
Y494527D03*
X72500Y496673D03*
Y491673D03*
X104000Y531000D03*
X71000Y530748D03*
X96000Y524000D03*
X68000Y533871D03*
Y537071D03*
X99500Y551845D03*
Y547445D03*
Y501452D03*
Y497052D03*
X105000Y557494D03*
Y510300D03*
Y507100D03*
Y491403D03*
Y488203D03*
X71000Y524464D03*
X99900Y582400D03*
X61100Y600100D03*
X61900Y584300D03*
X72900Y605400D03*
X94700Y599800D03*
X80000Y600000D03*
X108917Y562488D03*
X72500Y571673D03*
X96000Y563819D03*
X89400Y603250D03*
X95900Y605500D03*
X62426Y607740D03*
X105000Y560694D03*
X88600Y623300D03*
X85250Y652750D03*
X61500Y682500D03*
X59000Y659500D03*
X49000Y638000D03*
X76500Y665000D03*
X80153Y635758D03*
X85223Y645227D03*
X70500Y648500D03*
X48000Y649500D03*
X46500Y653500D03*
X80300Y639977D03*
X50560Y653500D03*
X97000Y772100D03*
X87075Y768250D03*
X102500Y737500D03*
X83200Y768300D03*
X76000Y706500D03*
X62000Y736500D03*
X61500Y748000D03*
X51500Y730500D03*
Y757500D03*
X106500Y771500D03*
X110000D03*
Y768000D03*
X106500D03*
X86900Y774750D03*
X49500Y771000D03*
X67500Y822500D03*
X63100Y788800D03*
X73500Y779500D03*
X100600Y811300D03*
X104600D03*
X108100D03*
X97100D03*
X112500Y848700D03*
Y845200D03*
X80215Y777137D03*
X109040Y873334D03*
X109000Y892130D03*
X109187Y911424D03*
X51000Y913500D03*
X63500Y899000D03*
X65500Y867500D03*
X98300Y850400D03*
X109040Y879500D03*
X109000Y898500D03*
X109187Y917000D03*
X96000Y918937D03*
Y909488D03*
Y900039D03*
Y890591D03*
Y881142D03*
Y871692D03*
Y862244D03*
X72500Y902185D03*
Y897185D03*
X71000Y869000D03*
X47500Y901500D03*
X99500Y906964D03*
Y902564D03*
Y888066D03*
Y883666D03*
Y869168D03*
Y864768D03*
X105000Y915812D03*
Y912612D03*
Y896915D03*
Y893715D03*
Y878017D03*
Y874817D03*
X72500Y872185D03*
X67500Y935111D03*
X109000Y961212D03*
X67000Y953500D03*
X96532Y977682D03*
X107400Y994000D03*
X67500Y946855D03*
X109000Y968000D03*
X72500Y977185D03*
X96000Y969331D03*
X72500Y962185D03*
X96000Y959882D03*
X72500Y947185D03*
X96000Y950433D03*
Y945000D03*
Y934685D03*
Y925236D03*
X104000Y936000D03*
X96000Y930000D03*
X71000Y936260D03*
X68000Y939383D03*
Y942583D03*
X99500Y957357D03*
Y952957D03*
X105000Y966206D03*
Y963006D03*
X65500Y927500D03*
X71000Y925500D03*
X99600Y1001400D03*
X102403Y1058209D03*
X103200Y1042500D03*
X83248Y1059636D03*
X93000Y1005700D03*
X81689Y1039600D03*
X77750Y1056750D03*
X96500Y1011200D03*
X64037Y1016654D03*
X74000Y1047500D03*
X41000Y1057500D03*
X81689Y1049400D03*
X106100Y1030000D03*
X71000Y1109000D03*
X42286Y1089500D03*
Y1085500D03*
X67090Y1070360D03*
X41608Y1125065D03*
X39959Y1128308D03*
X96100Y1176700D03*
X87900Y1173300D03*
X111500Y1145000D03*
X75000Y1182500D03*
X41500Y1165500D03*
Y1178000D03*
X67500Y1191500D03*
X110000Y1173500D03*
X106500D03*
X110000Y1177000D03*
X106500D03*
X88500Y1177300D03*
X40097Y1142513D03*
X85300Y1182000D03*
X109040Y1278846D03*
X81500Y1213000D03*
X99100Y1219800D03*
X104500Y1217000D03*
X108000D03*
X95700Y1219700D03*
X112600Y1254300D03*
X98300Y1255900D03*
X109040Y1285012D03*
X96000Y1277205D03*
Y1267756D03*
X71000Y1274500D03*
X112600Y1250800D03*
X99500Y1274680D03*
Y1270280D03*
X105000Y1283529D03*
Y1280329D03*
X72500Y1277697D03*
X109000Y1297642D03*
X109133Y1316936D03*
X67500Y1340624D03*
X64000Y1328500D03*
X58500Y1320500D03*
X67500Y1352366D03*
X109000Y1304012D03*
X109133Y1322512D03*
X72500Y1352697D03*
X96000Y1355945D03*
Y1350500D03*
Y1340197D03*
Y1330748D03*
Y1324449D03*
Y1315000D03*
Y1305551D03*
Y1296103D03*
Y1286654D03*
X72500Y1307697D03*
Y1302697D03*
X104000Y1341000D03*
X71000Y1341772D03*
X96000Y1335000D03*
X68000Y1344895D03*
Y1348095D03*
X99500Y1312476D03*
Y1308076D03*
Y1293578D03*
Y1289178D03*
X105000Y1321324D03*
Y1318124D03*
Y1302427D03*
Y1299227D03*
X71000Y1335488D03*
X58900Y1317000D03*
X109000Y1366724D03*
Y1373512D03*
X70838Y1384165D03*
X96000Y1374843D03*
X72285Y1365633D03*
X96000Y1365393D03*
X96250Y1414400D03*
X62962Y1422600D03*
X100000Y1423000D03*
X99900Y1419600D03*
X99500Y1362869D03*
Y1358469D03*
X105000Y1371718D03*
Y1368518D03*
X48000Y1482000D03*
X82748Y1465560D03*
X80000Y1480000D03*
X109500Y1486000D03*
X110000Y1470000D03*
X99300Y1431200D03*
X82748Y1455148D03*
X76750Y1462762D03*
X80153Y1446781D03*
X73000Y1455100D03*
X69365Y1474719D03*
X80300Y1451000D03*
X88076Y1575924D03*
X90500Y1521500D03*
X96000Y1541100D03*
X72000Y1551500D03*
X72100Y1536400D03*
Y1509900D03*
X48000Y1505500D03*
X91125Y1565900D03*
X105700Y1548200D03*
X82005Y1540500D03*
X85808D03*
X110500Y1573200D03*
X107000D03*
X103500D03*
X80465Y1570120D03*
X109050Y1540600D03*
X46893Y1519979D03*
X47368Y1527323D03*
X42644Y1521957D03*
X46845Y1514264D03*
X43000Y1526000D03*
X42960Y1517408D03*
X64500Y1581500D03*
X100500Y1622500D03*
X104500D03*
X108000D03*
X97000D03*
X40500Y1608500D03*
X107000Y1576700D03*
X103500D03*
X110500D03*
X42919Y1583175D03*
X64525Y1591016D03*
X109040Y1684358D03*
X109000Y1703154D03*
X66500Y1694000D03*
X68000Y1651500D03*
X98600Y1659800D03*
X109040Y1690524D03*
X109000Y1709524D03*
X96000Y1701615D03*
Y1711063D03*
Y1673268D03*
X72500Y1708209D03*
X96000Y1682716D03*
Y1692166D03*
X71000Y1680000D03*
X72500Y1713209D03*
X96000Y1720512D03*
X99500Y1713588D03*
Y1717988D03*
Y1694690D03*
Y1699090D03*
Y1675792D03*
Y1680192D03*
X105000Y1704739D03*
Y1707939D03*
Y1685841D03*
Y1689041D03*
X72500Y1683209D03*
X51635Y1665355D03*
X66400Y1706900D03*
X109137Y1722448D03*
X67500Y1757886D03*
X109030Y1778736D03*
X100000Y1780000D03*
X67500Y1746128D03*
X109137Y1728024D03*
X109030Y1772524D03*
X96000Y1729961D03*
Y1736260D03*
Y1745109D03*
Y1755158D03*
Y1761457D03*
Y1770906D03*
X72500Y1758209D03*
Y1773209D03*
Y1788209D03*
X96000Y1780355D03*
X100000Y1759000D03*
X71000Y1747284D03*
X104000Y1747800D03*
X68000Y1750407D03*
Y1753607D03*
X99500Y1763981D03*
Y1768381D03*
X105000Y1774030D03*
Y1777230D03*
Y1723636D03*
Y1726836D03*
X67000Y1738000D03*
X71015D03*
X93600Y1848200D03*
X45100Y1850800D03*
X42300Y1846750D03*
X42200Y1859050D03*
X45200Y1839300D03*
Y1843300D03*
Y1854700D03*
X40800Y1832300D03*
Y1827300D03*
X76975Y1864000D03*
X100300Y1820800D03*
X77159Y1818277D03*
X91036Y1835282D03*
X72123Y1841183D03*
X100287Y1825915D03*
X100300Y1830000D03*
X80600Y1848900D03*
X98000Y1848800D03*
X85000Y1817100D03*
X74100Y1796200D03*
X67800Y1855200D03*
X93625Y1802200D03*
X52000Y1877500D03*
X100000Y1928000D03*
X80000D03*
X60000D03*
X74300Y1900000D03*
X107543Y1898024D03*
X111000Y1879570D03*
X100100Y1896300D03*
X80000Y1920000D03*
X60000D03*
Y1900000D03*
X44000D03*
X40556Y1917072D03*
X40000Y1940000D03*
X52000Y1887500D03*
X41700Y1883700D03*
X42100Y1871350D03*
X112366Y1883985D03*
X46868Y1887765D03*
X60897Y1885848D03*
X48000Y1877500D03*
X110700Y1974100D03*
X80000Y1980000D03*
X100300Y1980900D03*
X71666Y1961325D03*
X43935Y1957215D03*
X56875Y1954250D03*
X40000Y1980000D03*
X112559Y1986626D03*
X92559D03*
X72559D03*
X52559D03*
X94700Y1974100D03*
X98800D03*
X103300D03*
X107000D03*
X80400Y1957900D03*
X73400D03*
X76900D03*
X87500Y1954300D03*
X80400Y1954400D03*
X83900D03*
X73400D03*
X76900D03*
X57800Y1961800D03*
X170034Y31475D03*
X155018Y5500D03*
X170018D03*
X116600Y46800D03*
X177300Y39000D03*
X180800D03*
X184300D03*
X180800Y35500D03*
X177300D03*
X184300D03*
X152400Y41500D03*
X180000Y80000D03*
X160000D03*
X140000D03*
X154700Y65000D03*
X150200D03*
X141700Y64900D03*
X138200D03*
X131700Y61300D03*
X128200D03*
X121600Y54700D03*
X184461Y103368D03*
X125700Y54400D03*
X179147Y137913D03*
X180000Y180000D03*
X124000Y135859D03*
Y124059D03*
X147125Y160500D03*
X158300Y135200D03*
X150557Y142854D03*
X167298Y147703D03*
X159500Y181000D03*
X124000Y128359D03*
Y131559D03*
X167298Y151203D03*
X114579Y137775D03*
X154875Y160500D03*
X135064Y213390D03*
X134941Y264178D03*
X135500Y200500D03*
X125500Y265500D03*
X132500Y236000D03*
X128500Y248000D03*
X176492Y231103D03*
X180100Y231095D03*
X135064Y219602D03*
X171595Y203917D03*
X148095Y211771D03*
X171595Y218917D03*
X148095Y221220D03*
X171595Y233917D03*
X148095Y230669D03*
Y236968D03*
Y246417D03*
Y255866D03*
Y262165D03*
X140000Y247500D03*
X173095Y244842D03*
X148000Y241500D03*
X180000Y235394D03*
X176800D03*
X144595Y223745D03*
Y228145D03*
X139095Y214896D03*
Y218096D03*
Y265290D03*
X172900Y249400D03*
X143600Y252100D03*
X129000Y255500D03*
X135095Y288972D03*
X134995Y301768D03*
X126000Y293000D03*
X125000Y312000D03*
X145800Y332400D03*
X131300D03*
X134941Y269602D03*
X135095Y282602D03*
X134995Y307602D03*
X148095Y271614D03*
Y281063D03*
Y290511D03*
Y299960D03*
Y309409D03*
Y318858D03*
X171595Y278917D03*
Y283917D03*
X173000Y312500D03*
X131300Y335900D03*
X126445Y338300D03*
X114295D03*
X144595Y274138D03*
Y278538D03*
Y293036D03*
Y297436D03*
Y311934D03*
Y316334D03*
X139095Y268490D03*
Y284187D03*
Y287387D03*
Y303085D03*
Y306285D03*
X171595Y308917D03*
X145900Y408500D03*
X119159Y405100D03*
X124466Y370025D03*
X143500Y370000D03*
X147000D03*
X139500D03*
X136000D03*
X134000Y409500D03*
X137500D03*
X130500D03*
X127000D03*
X117000Y362500D03*
Y366000D03*
X113500Y362500D03*
Y366000D03*
X173800Y379800D03*
X157200Y412000D03*
X158500Y408000D03*
X148700Y413400D03*
X180000Y480000D03*
X163500Y423000D03*
X180000Y460000D03*
X120000D03*
X140000Y480000D03*
Y460000D03*
X160000Y440000D03*
X140000D03*
X120800Y438000D03*
X127000Y413000D03*
X130500D03*
X134000D03*
X137500D03*
X170500Y478500D03*
X125300Y438000D03*
X157500Y551200D03*
X160000Y520000D03*
X180000D03*
X124000Y541373D03*
Y529573D03*
X165138Y536500D03*
X174000Y553500D03*
X157750Y541250D03*
X184500Y553500D03*
X124000Y533873D03*
Y537073D03*
X157750Y544750D03*
X135095Y625402D03*
X158500Y569500D03*
X131500Y610500D03*
X180000Y620000D03*
Y580000D03*
X139500Y600400D03*
X180000Y600000D03*
X135095Y618614D03*
X171595Y609429D03*
X148095Y617283D03*
X171595Y624429D03*
X148095Y626732D03*
X132350Y563750D03*
X159600Y581400D03*
X155500Y574000D03*
X144595Y629257D03*
X139095Y620408D03*
Y623608D03*
X150850Y574350D03*
X134941Y669690D03*
X135095Y694484D03*
X176492Y636617D03*
X180308D03*
X134941Y675114D03*
X135095Y688114D03*
X171895Y639429D03*
X148095Y636181D03*
Y642480D03*
Y651929D03*
Y661378D03*
Y667677D03*
Y677126D03*
Y686575D03*
Y696023D03*
X171595Y684429D03*
Y689429D03*
X140000Y654000D03*
X148000Y648000D03*
X173095Y650354D03*
X180000Y640906D03*
X176800D03*
X144595Y633657D03*
Y679650D03*
Y684050D03*
Y698548D03*
Y702948D03*
X139095Y670802D03*
Y674002D03*
Y689699D03*
Y692899D03*
X173000Y655200D03*
X134993Y707280D03*
X124966Y775525D03*
X125500Y719000D03*
X180000Y720000D03*
X136100Y775600D03*
X139600D03*
X147100D03*
X143600D03*
X145800Y737100D03*
X131400Y738200D03*
X134993Y713114D03*
X148095Y705472D03*
Y714921D03*
Y724370D03*
X173000Y718000D03*
X131400Y741700D03*
X122445Y743800D03*
X117000Y771500D03*
Y768000D03*
X113500Y771500D03*
Y768000D03*
X117945Y743800D03*
X144595Y717446D03*
Y721846D03*
X139095Y708597D03*
Y711797D03*
X171595Y714429D03*
X148600Y818700D03*
X147100Y814200D03*
X119534Y810975D03*
X116000Y814500D03*
X122251Y842400D03*
X127000Y818500D03*
X130500D03*
X134000D03*
X137500D03*
X134000Y815000D03*
X137500D03*
X130500D03*
X127000D03*
X156800Y816000D03*
X126800Y842500D03*
X143800Y807400D03*
X160000Y880000D03*
X140000Y900000D03*
X182000Y949000D03*
X180000Y980000D03*
X167000Y945909D03*
Y935909D03*
X178000Y960000D03*
X162200Y988000D03*
X161095Y980622D03*
X167000Y939309D03*
Y942509D03*
X174500Y960000D03*
X157200Y950800D03*
X155900Y954200D03*
X157000Y957500D03*
X161200Y946100D03*
X161700Y950800D03*
X135095Y1030914D03*
X180000Y1000000D03*
X176492Y1042129D03*
X180308D03*
X135095Y1024126D03*
X171595Y1014941D03*
X148095Y1022795D03*
X171595Y1029941D03*
X148095Y1032244D03*
X171595Y1044941D03*
X148095Y1041693D03*
Y1047992D03*
Y1057441D03*
Y1066890D03*
X140000Y1059500D03*
X129000Y1051500D03*
X173095Y1055866D03*
X148000Y1053500D03*
X180000Y1046418D03*
X176800D03*
X144595Y1034769D03*
Y1039169D03*
X139095Y1025920D03*
Y1029120D03*
X137500Y1014500D03*
X173000Y1060400D03*
X139300Y1067000D03*
X134941Y1075202D03*
X135095Y1099996D03*
X135001Y1112792D03*
X180000Y1140000D03*
X129500Y1084500D03*
X122500Y1107000D03*
X123500Y1123500D03*
X180000Y1120000D03*
Y1100000D03*
Y1080000D03*
X147800Y1140000D03*
X134941Y1080626D03*
X135095Y1093626D03*
X135001Y1118626D03*
X148095Y1073189D03*
Y1082638D03*
Y1092087D03*
Y1101535D03*
Y1110984D03*
Y1120433D03*
Y1129882D03*
X171595Y1089941D03*
Y1094941D03*
X173000Y1123500D03*
X144595Y1085162D03*
Y1089562D03*
Y1104060D03*
Y1108460D03*
Y1122958D03*
Y1127358D03*
X139095Y1076314D03*
Y1079514D03*
Y1095211D03*
Y1098411D03*
Y1114109D03*
Y1117309D03*
X171595Y1119941D03*
X124100Y1181025D03*
X143500Y1180400D03*
X147000D03*
X139500D03*
X136000D03*
X131500Y1143200D03*
Y1146700D03*
X122400Y1149200D03*
X117000Y1173500D03*
Y1177000D03*
X113500Y1173500D03*
Y1177000D03*
X117900Y1149200D03*
X146700Y1219600D03*
X119534Y1216475D03*
X157325Y1223850D03*
X120000Y1280000D03*
X140000D03*
X160000D03*
X180000D03*
X120000Y1220000D03*
X180000D03*
X118250Y1252050D03*
X127000Y1224000D03*
X130500Y1220500D03*
Y1224000D03*
X134000D03*
X137500D03*
X134000Y1220500D03*
X137500D03*
X127000D03*
X158052Y1216052D03*
X129150Y1252050D03*
X179147Y1353048D03*
X160000Y1340000D03*
X180000D03*
X140000D03*
Y1300000D03*
X160000D03*
X180000D03*
X129500Y1352321D03*
Y1340521D03*
X147956Y1347802D03*
X129500Y1344821D03*
Y1348021D03*
X154709Y1344513D03*
X121320Y1425396D03*
X117690Y1397168D03*
X143087Y1403623D03*
X180000Y1400000D03*
Y1420000D03*
X135095Y1429638D03*
X171595Y1420453D03*
X148095Y1428307D03*
X160000Y1360000D03*
X151125Y1376608D03*
X140125Y1381300D03*
X167301Y1363238D03*
Y1366838D03*
X158875Y1376100D03*
X135095Y1436426D03*
X134935Y1480714D03*
X126916Y1447364D03*
X180000Y1440000D03*
Y1500000D03*
X176492Y1447634D03*
X180308D03*
X134935Y1486138D03*
X135095Y1499138D03*
X171595Y1435453D03*
X148095Y1437756D03*
X171895Y1450453D03*
X148095Y1447205D03*
Y1453504D03*
Y1462953D03*
Y1472402D03*
Y1478701D03*
Y1488150D03*
Y1497599D03*
X171595Y1495453D03*
Y1500453D03*
X130000Y1470000D03*
X122000D03*
X114000D03*
X140000Y1464000D03*
X118000Y1470000D03*
X148000Y1458000D03*
X126000Y1466000D03*
X173095Y1461378D03*
X180000Y1451930D03*
X176800D03*
X144595Y1440281D03*
Y1444681D03*
Y1490674D03*
Y1495074D03*
X139095Y1431432D03*
Y1434632D03*
Y1481826D03*
Y1485026D03*
Y1500723D03*
X148095Y1468752D03*
X173100Y1466300D03*
X135095Y1505508D03*
X134995Y1518304D03*
X147700Y1545500D03*
X123400Y1522600D03*
X116500Y1505500D03*
X180000Y1520000D03*
X130600Y1549100D03*
X134995Y1524138D03*
X148095Y1507047D03*
Y1516496D03*
Y1525945D03*
Y1535394D03*
X173000Y1529000D03*
X123500Y1505200D03*
X144200Y1545500D03*
X114000Y1573200D03*
X128250Y1506500D03*
X144595Y1509572D03*
Y1513972D03*
Y1528470D03*
Y1532870D03*
X139095Y1503923D03*
Y1519621D03*
Y1522821D03*
X171595Y1525453D03*
X143500Y1625500D03*
X119534Y1621975D03*
X113841Y1580900D03*
X153700Y1633600D03*
X181500Y1641500D03*
X182500Y1622500D03*
X172000Y1595000D03*
X171500Y1613500D03*
X143300Y1586900D03*
X146800D03*
X138800Y1585100D03*
X135300D03*
X126800Y1630100D03*
X130300D03*
X133800D03*
X126800Y1626600D03*
X130300D03*
X137300Y1630100D03*
Y1626600D03*
X133800D03*
X114000Y1576700D03*
X150200Y1628000D03*
X160200Y1710300D03*
X117300Y1696500D03*
X136600Y1681900D03*
X121700Y1654800D03*
X143000Y1656000D03*
X137000Y1666500D03*
X120000Y1678000D03*
X123000Y1702000D03*
X136700Y1720100D03*
X160000Y1720000D03*
Y1700000D03*
X180000D03*
Y1680000D03*
X113200Y1659800D03*
Y1656300D03*
X117000Y1654600D03*
X126900Y1654700D03*
X144400Y1720400D03*
X159800Y1730000D03*
X148000Y1787000D03*
X125000Y1757834D03*
Y1746034D03*
X177717Y1778162D03*
X180075Y1790692D03*
X125000Y1750334D03*
Y1753534D03*
X136500Y1733000D03*
X137000Y1727500D03*
X140825Y1729825D03*
X157898Y1780145D03*
X140300Y1724100D03*
X147200Y1724400D03*
X135065Y1835438D03*
X128800Y1854000D03*
X145500Y1807500D03*
X136500Y1811500D03*
X140000Y1820000D03*
X160000Y1800000D03*
X180000D03*
Y1840000D03*
X180308Y1853146D03*
X176492D03*
X135065Y1841650D03*
X171595Y1825965D03*
X148095Y1833819D03*
X171595Y1840965D03*
X148095Y1843268D03*
X171595Y1855965D03*
X148095Y1852717D03*
Y1859016D03*
X173095Y1866890D03*
X148000Y1864000D03*
X180000Y1857442D03*
X176800D03*
X144595Y1850193D03*
Y1845793D03*
X139095Y1840144D03*
Y1836944D03*
X151452Y1810000D03*
X134895Y1905020D03*
X128800Y1921300D03*
X129500Y1883500D03*
X115228Y1879770D03*
X128200Y1900300D03*
X180000Y1880000D03*
Y1900000D03*
Y1940000D03*
X134895Y1886150D03*
Y1891650D03*
Y1910650D03*
X134995Y1923650D03*
Y1929650D03*
X148095Y1868465D03*
Y1877914D03*
Y1884213D03*
Y1893662D03*
Y1903111D03*
Y1912559D03*
Y1922008D03*
Y1931457D03*
X171595Y1900965D03*
Y1905965D03*
X173000Y1934500D03*
X140000Y1870000D03*
X144595Y1900586D03*
Y1896186D03*
Y1919484D03*
Y1915084D03*
Y1938382D03*
Y1933982D03*
X139095Y1890538D03*
Y1887338D03*
Y1909435D03*
Y1906235D03*
Y1928333D03*
Y1925133D03*
X171595Y1930965D03*
X113500Y1875970D03*
X173500Y1871700D03*
X133000Y1977100D03*
X114200Y1974100D03*
X118500Y1971400D03*
X139100Y1977100D03*
X172559Y1986626D03*
X152559D03*
X132559D03*
X148095Y1940906D03*
X123200Y1947250D03*
X130500Y1946200D03*
X137300Y1969900D03*
X136800Y1959900D03*
X150800Y1958900D03*
X150600Y1970300D03*
X196665Y35585D03*
X205625Y38750D03*
X240000Y20000D03*
Y40000D03*
X230018Y5500D03*
X250018D03*
X190018D03*
X210018D03*
X187800Y39000D03*
Y35500D03*
X208150Y32250D03*
X220000Y80000D03*
X240000D03*
X200000D03*
X220500Y67500D03*
X240000Y140000D03*
X220000D03*
Y160000D03*
X240000D03*
X200000Y180000D03*
X220000D03*
X240000D03*
X198800Y158000D03*
Y162500D03*
Y167000D03*
X194500Y236902D03*
X200000Y200000D03*
X240000Y220000D03*
X220000D03*
Y200000D03*
X240000D03*
X200000Y260000D03*
X240000D03*
X220000D03*
X194500Y243300D03*
X190500Y238501D03*
Y241701D03*
X200000Y280000D03*
X220000D03*
X240000D03*
Y320000D03*
Y300000D03*
X220000D03*
X200000D03*
Y320000D03*
X220000D03*
X240000Y340000D03*
X220000Y360000D03*
X240000D03*
X220000Y340000D03*
X200000D03*
Y360000D03*
X220000Y480000D03*
X200000D03*
X220000Y460000D03*
X200000D03*
X220000Y420000D03*
X200000Y440000D03*
Y420000D03*
Y520000D03*
X220000D03*
X195500Y531250D03*
Y546250D03*
Y538750D03*
X188854Y527099D03*
Y530902D03*
X206500Y538750D03*
Y546250D03*
Y531250D03*
X220000Y620000D03*
X240000Y600000D03*
Y580000D03*
X200000D03*
X195250Y561300D03*
Y576700D03*
X200250Y572100D03*
X190500Y639713D03*
X200000Y700000D03*
X220000D03*
Y680000D03*
X200000D03*
Y660000D03*
X220000D03*
Y640000D03*
X190500Y651513D03*
Y644013D03*
Y647213D03*
X240000Y760000D03*
X220000Y720000D03*
Y740000D03*
X200000Y760000D03*
Y740000D03*
Y720000D03*
X214700Y784200D03*
X200000Y900000D03*
X240000Y860000D03*
X220000D03*
Y880000D03*
X240000D03*
X190330Y913530D03*
X194200Y985900D03*
X220000Y940000D03*
X240000D03*
X201125Y957200D03*
X195500Y949750D03*
X198900Y969500D03*
X207350Y968627D03*
X198900Y974000D03*
Y978500D03*
X229500Y946600D03*
X198900Y965477D03*
X208875Y957200D03*
X190600Y1045226D03*
X220000Y1040000D03*
Y1020000D03*
X240000D03*
Y1000000D03*
Y1060000D03*
X220000D03*
X240000Y1040000D03*
X190600Y1057024D03*
X190500Y1049525D03*
Y1052725D03*
X200000Y1080000D03*
Y1100000D03*
Y1140000D03*
Y1120000D03*
X220000Y1140000D03*
Y1120000D03*
X240000D03*
Y1100000D03*
X220000D03*
Y1080000D03*
X240000D03*
X255674Y1099470D03*
X196000Y1070300D03*
X208500Y1190000D03*
X200000Y1200000D03*
X240000D03*
Y1180000D03*
X200000Y1160000D03*
Y1280000D03*
X220000D03*
X240000D03*
Y1220000D03*
X220000D03*
X200000Y1340000D03*
X220000D03*
X240000D03*
X200000Y1300000D03*
X220000D03*
X240000D03*
X227000Y1359500D03*
X215000Y1368000D03*
X240000Y1367500D03*
Y1420000D03*
Y1400000D03*
X193400Y1373000D03*
Y1377500D03*
Y1382000D03*
X190400Y1462536D03*
X240000Y1460000D03*
Y1440000D03*
X200000D03*
Y1460000D03*
Y1480000D03*
X240000D03*
Y1500000D03*
X200000D03*
X190400Y1450738D03*
X214500Y1459000D03*
X190500Y1455037D03*
Y1458237D03*
X202000Y1534000D03*
X200000Y1520000D03*
X220000D03*
X240000D03*
X200000Y1560000D03*
X220000D03*
X240000D03*
X203500Y1618500D03*
X229500Y1614500D03*
X189300Y1577200D03*
X220000Y1580000D03*
X248500Y1713005D03*
Y1716808D03*
X242500Y1702500D03*
X251800Y1718400D03*
X220000Y1720000D03*
X200000Y1660000D03*
Y1680000D03*
X220000D03*
Y1660000D03*
X240000Y1680000D03*
Y1660000D03*
X220200Y1740900D03*
X206000Y1735000D03*
X256000Y1745500D03*
X220000Y1734500D03*
X207600Y1777500D03*
X220800Y1763750D03*
X191353Y1772940D03*
X197900Y1781500D03*
X251900Y1769900D03*
X203299Y1763350D03*
X197900Y1786000D03*
Y1790500D03*
X222500Y1776200D03*
X255495Y1738573D03*
X251692D03*
X203299Y1759750D03*
X224875Y1768100D03*
X194620Y1859298D03*
X200000Y1800000D03*
X220000D03*
X240000D03*
X220000Y1840000D03*
X240000D03*
X194620Y1865000D03*
X190500Y1860549D03*
Y1863749D03*
X200000Y1880000D03*
Y1900000D03*
X220000D03*
X240000Y1920000D03*
X220000D03*
X200000D03*
Y1940000D03*
X220000D03*
X240000D03*
X256549Y1898366D03*
X240000Y1880000D03*
X256500D03*
X200000Y1980000D03*
Y1960000D03*
X220000Y1980000D03*
Y1960000D03*
X240000Y1980000D03*
Y1960000D03*
X252559Y1986626D03*
X232559D03*
X212559D03*
X192559D03*
X300000Y40000D03*
Y20000D03*
X320000D03*
Y40000D03*
X260000D03*
Y20000D03*
X280000D03*
Y40000D03*
X310018Y5500D03*
X330018D03*
X270018D03*
X290018D03*
X320000Y80000D03*
X300000Y60000D03*
X320000D03*
Y120000D03*
X300000D03*
X280000D03*
X260000Y100000D03*
X280000D03*
X300000D03*
X320000D03*
X300000Y80000D03*
X280000D03*
X260000D03*
Y160000D03*
X320000D03*
X300000Y140000D03*
X320000D03*
X260000Y180000D03*
X280000D03*
X292600Y166955D03*
X280000Y220000D03*
X260000D03*
Y200000D03*
X280000D03*
X300000D03*
Y220000D03*
X320000D03*
Y240000D03*
Y320000D03*
X300000D03*
X280000D03*
X260000D03*
X320000Y280000D03*
X300000D03*
X260000Y300000D03*
X318656Y391440D03*
X326156D03*
X280000Y360000D03*
X260000D03*
Y340000D03*
X280000D03*
X300000D03*
X320000D03*
X304553Y374081D03*
X313500Y386000D03*
X309000Y365000D03*
X313500Y362000D03*
X320000Y359500D03*
X327500Y373000D03*
X305100Y407700D03*
X293000Y385000D03*
X294500Y408000D03*
X315000Y412000D03*
X321400Y404400D03*
X327500Y377000D03*
X321500Y408500D03*
X312500Y393050D03*
X304400Y416200D03*
X280000Y460000D03*
Y480000D03*
X300000D03*
Y460000D03*
X320000D03*
X300000Y440000D03*
X280000D03*
Y420000D03*
X260000D03*
Y440000D03*
Y480000D03*
Y460000D03*
X321500Y413000D03*
X303200Y422600D03*
X313200Y427500D03*
X317000D03*
X321500Y425200D03*
Y417000D03*
Y421000D03*
X260000Y520000D03*
X320000Y540000D03*
X296470Y555500D03*
X292667D03*
X297300Y505017D03*
X260000Y560000D03*
Y600000D03*
X280000Y620000D03*
X260000D03*
X302500Y583000D03*
X297500D03*
Y588000D03*
X302500D03*
X300000Y585500D03*
X288000Y586484D03*
X313000Y559000D03*
X329600Y583200D03*
X273500Y597000D03*
Y589000D03*
Y585000D03*
Y577000D03*
X284000Y612000D03*
X273500Y573000D03*
Y565000D03*
X296000Y612000D03*
X292000D03*
X316000D03*
X308000D03*
X304000D03*
X290580Y559000D03*
X298450D03*
X320100Y587200D03*
X317500Y559000D03*
X286130Y615700D03*
X270000Y579030D03*
X310030Y615500D03*
X298030Y621000D03*
X269800Y590930D03*
X270000Y567130D03*
X289933Y615700D03*
X270000Y582833D03*
X313833Y615500D03*
X301833Y621000D03*
X269800Y594733D03*
X270000Y570933D03*
X298500Y660200D03*
Y680200D03*
X320000Y700000D03*
X260000D03*
X320000Y640000D03*
X300000D03*
X280000D03*
X260000D03*
X298200Y720000D03*
X260000D03*
X320000D03*
X293500Y738000D03*
X326167Y811099D03*
Y814902D03*
X304400Y846700D03*
X321500Y807000D03*
X297840Y804552D03*
X280000Y820000D03*
X325053Y782652D03*
X309000Y795000D03*
X321500Y843000D03*
X323000Y819500D03*
X313500Y792000D03*
X320000Y789500D03*
X327500Y803000D03*
X304500Y836700D03*
X301300Y822550D03*
X292000Y837000D03*
X321500Y847000D03*
X315000Y842000D03*
X321500Y838500D03*
X321400Y834400D03*
X327500Y807000D03*
X312000Y824500D03*
X260000Y860000D03*
Y880000D03*
X300000D03*
X280000D03*
Y860000D03*
X295200Y903000D03*
X305200D03*
Y913000D03*
X295200D03*
X303500Y853100D03*
X321500Y855200D03*
Y851000D03*
X317000Y857900D03*
X313200D03*
X260000Y940000D03*
X280000D03*
X300000D03*
X260000Y980000D03*
X280000D03*
X300000D03*
X292500Y965500D03*
X320000Y1060000D03*
X300000D03*
X260000D03*
Y1040000D03*
X280000D03*
X300000D03*
X320000D03*
Y1020000D03*
X280000D03*
X300000D03*
X260000D03*
X280000Y1000000D03*
X300000D03*
X320000D03*
Y1140000D03*
X260000Y1120000D03*
X280000D03*
X300000D03*
X320000Y1100000D03*
X300000D03*
Y1080000D03*
X320000D03*
X294000Y1111500D03*
X260000Y1200000D03*
X280000D03*
Y1180000D03*
X260000Y1160000D03*
X296011Y1185470D03*
X309000Y1166500D03*
X295400Y1172655D03*
X313500Y1187500D03*
X320000Y1161000D03*
X327500Y1174500D03*
X305200Y1208300D03*
X321400Y1205900D03*
X321500Y1210000D03*
X327500Y1178500D03*
X312500Y1194000D03*
X304500Y1217500D03*
X320000Y1280000D03*
X300000Y1240000D03*
X320000Y1260000D03*
X300000Y1280000D03*
Y1260000D03*
X280000Y1280000D03*
X260000D03*
Y1260000D03*
X280000D03*
Y1220000D03*
X260000D03*
X321500Y1214500D03*
X295000Y1245000D03*
X294500Y1254000D03*
X302500Y1224000D03*
X321600Y1226600D03*
X313200Y1228800D03*
X317000D03*
X314437Y1213382D03*
X321500Y1222500D03*
Y1218500D03*
X280000Y1340000D03*
X260000D03*
X300000Y1300000D03*
X280000D03*
X260000D03*
X287167Y1380000D03*
X290970D03*
X311500Y1389000D03*
X280000Y1380000D03*
X260000Y1400000D03*
Y1420000D03*
X300000Y1421500D03*
X302500Y1424000D03*
X297500D03*
Y1419000D03*
X302500D03*
X303500Y1389000D03*
X297600Y1392000D03*
X273500Y1407500D03*
X319500Y1389000D03*
X301400Y1401500D03*
X315500Y1389000D03*
X293100Y1383500D03*
X284900D03*
X273500Y1419500D03*
Y1411500D03*
Y1423500D03*
X326500Y1417500D03*
Y1425700D03*
Y1405400D03*
Y1413500D03*
Y1429700D03*
X328000Y1381500D03*
Y1374000D03*
X327500Y1368500D03*
X273500Y1403500D03*
X307500Y1389000D03*
X330000Y1423470D03*
X270100Y1425697D03*
X330300Y1411100D03*
X270000Y1413530D03*
X330000Y1419667D03*
X270100Y1429500D03*
X330300Y1407297D03*
X270000Y1417333D03*
X260000Y1440000D03*
X300984Y1433500D03*
X273500Y1431500D03*
X287600Y1448000D03*
X279650D03*
X299600D03*
X291600D03*
X326500Y1437700D03*
X311600Y1448000D03*
X303600D03*
X330000Y1435170D03*
X293830Y1451500D03*
X305830Y1451300D03*
X282030Y1451400D03*
X330000Y1431367D03*
X297633Y1451500D03*
X309633Y1451300D03*
X285833Y1451400D03*
X260000Y1520000D03*
X280000D03*
X300000D03*
X320000Y1540000D03*
Y1560000D03*
X300000D03*
X280000D03*
X260000D03*
X258585Y1508386D03*
X260000Y1620000D03*
Y1600000D03*
X300000Y1620000D03*
X280000Y1600000D03*
Y1620000D03*
X300000Y1600000D03*
X320000D03*
X318156Y1692440D03*
X325656D03*
X289300Y1696200D03*
Y1701800D03*
X292200Y1688900D03*
X295800D03*
X306200Y1689400D03*
X259000Y1702500D03*
X260000Y1680000D03*
Y1660000D03*
X321500Y1713000D03*
X327500Y1673000D03*
X305300Y1715700D03*
X306200Y1709600D03*
X301800Y1722100D03*
X265500Y1722000D03*
X283500D03*
X285000Y1700600D03*
X295600Y1693400D03*
X285000Y1697400D03*
X292400Y1693400D03*
X315000Y1712000D03*
X321500Y1721000D03*
X327500Y1677000D03*
X321500Y1717000D03*
Y1708500D03*
X321400Y1704400D03*
X313500Y1692500D03*
X320000Y1760000D03*
Y1780000D03*
X260000Y1740000D03*
X288000Y1742500D03*
X293000D03*
X284000Y1731250D03*
X268800Y1774600D03*
X276402Y1726146D03*
X272599D03*
X297000Y1777000D03*
Y1752000D03*
X302000D03*
X321500Y1725200D03*
X317000Y1727300D03*
X313200D03*
X260000Y1800000D03*
Y1840000D03*
X280000D03*
X320000Y1860000D03*
X300000D03*
Y1840000D03*
X320000Y1820000D03*
Y1840000D03*
X271500Y1795000D03*
X279500D03*
X287500D03*
X300000Y1800000D03*
X320000Y1940000D03*
X300000D03*
X280000D03*
X260000D03*
X280071Y1924667D03*
X300000Y1900000D03*
Y1920000D03*
X320000D03*
Y1900000D03*
X300000Y1880000D03*
X320000D03*
X260000Y1980000D03*
Y1960000D03*
X280000Y1980000D03*
Y1960000D03*
X300000Y1980000D03*
Y1960000D03*
X320000Y1980000D03*
Y1960000D03*
X312559Y1986626D03*
X292559D03*
X272559D03*
X380000Y20000D03*
Y40000D03*
X400000D03*
Y20000D03*
X340000Y40000D03*
Y20000D03*
X360000Y40000D03*
Y20000D03*
X390018Y5500D03*
X350018D03*
X370018D03*
X400000Y100000D03*
Y80000D03*
X377500Y98000D03*
X400000Y60000D03*
X340000Y80000D03*
Y100000D03*
Y60000D03*
X400000Y120000D03*
X340000D03*
X373500Y98000D03*
X363750Y65250D03*
X352500Y68500D03*
X358500Y93500D03*
X374300Y81400D03*
X363750Y73300D03*
X378100Y81500D03*
X363750Y54250D03*
X382200Y81500D03*
X382000Y98000D03*
X358000Y64000D03*
X344500Y71750D03*
X340000Y180000D03*
X360000D03*
X380000D03*
X400000D03*
Y140000D03*
Y160000D03*
X380000Y140000D03*
Y160000D03*
X360000Y140000D03*
Y160000D03*
X340000D03*
Y140000D03*
X357250Y124000D03*
X360750D03*
X400000Y220000D03*
Y200000D03*
X380000D03*
X340000Y240000D03*
Y260000D03*
X360000D03*
Y280000D03*
X369000Y294000D03*
X370000Y411000D03*
Y405500D03*
X375500D03*
X381000D03*
X375500Y411000D03*
X381000D03*
X359000D03*
X364500D03*
Y405500D03*
X359000D03*
X370000Y400000D03*
X381000D03*
X375500D03*
X370000Y389000D03*
Y394500D03*
X375500D03*
Y389000D03*
X381000D03*
Y394500D03*
X364500Y400000D03*
X365000Y394500D03*
Y389000D03*
X359000D03*
Y394500D03*
Y400000D03*
X370128Y361337D03*
X349706Y355693D03*
X356250Y349000D03*
X337500Y406250D03*
X331500Y393000D03*
X368500Y364500D03*
X372000D03*
X401500Y401500D03*
X397000Y383750D03*
X383750Y349000D03*
X391800Y355800D03*
X401500Y410250D03*
X356257Y344176D03*
X391750Y344500D03*
X383750D03*
X348256Y344114D03*
X331500Y389000D03*
X365100Y371200D03*
X397000Y380250D03*
X375200Y371250D03*
X349870Y348870D03*
X331300Y408500D03*
X400000Y440000D03*
Y460000D03*
Y480000D03*
X339500Y416750D03*
X370397Y439122D03*
X368500Y436000D03*
X372000D03*
X397000Y414750D03*
X379250Y451000D03*
X385896Y444265D03*
X343750Y451000D03*
X350241Y444377D03*
X351729Y455810D03*
X379258Y455892D03*
X387249Y455882D03*
X343729Y455810D03*
X364758Y429249D03*
X375200Y429250D03*
X350137Y451250D03*
X385607Y451232D03*
X400000Y540000D03*
X340000D03*
X380000Y500000D03*
Y540000D03*
X400000Y520000D03*
X339500Y572667D03*
Y576470D03*
X400000Y560000D03*
X332500Y597000D03*
Y589000D03*
X360000Y580000D03*
X340000Y560000D03*
Y600000D03*
Y620000D03*
X380000D03*
X400000D03*
X380000Y560000D03*
X332500Y605000D03*
X336000Y570580D03*
Y578600D03*
X332500Y593000D03*
Y601000D03*
X380000Y660000D03*
X400000Y640000D03*
Y680000D03*
Y700000D03*
X340000Y660000D03*
Y680000D03*
Y700000D03*
X360000D03*
Y680000D03*
Y660000D03*
Y640000D03*
X380000D03*
X400000Y740000D03*
Y720000D03*
X340000Y740000D03*
Y720000D03*
X360000D03*
X377250Y774500D03*
X385238Y774122D03*
X400000Y780000D03*
X340000D03*
X370000Y841000D03*
Y835500D03*
X375500D03*
X381000D03*
X375500Y841000D03*
X381000D03*
X359000D03*
X364500D03*
Y835500D03*
X359000D03*
X370000Y830000D03*
X381000D03*
X375500D03*
X370000Y819000D03*
Y824500D03*
X375500D03*
Y819000D03*
X381000D03*
Y824500D03*
X364500Y830000D03*
X365000Y824500D03*
Y819000D03*
X359000D03*
Y824500D03*
Y830000D03*
X362000Y797000D03*
X365500D03*
X358000Y794000D03*
X397000Y844750D03*
X339500Y846750D03*
X337500Y836250D03*
X331500Y823000D03*
X401500Y836000D03*
X377250Y779000D03*
X385250Y785700D03*
X395000Y806500D03*
X331500Y819000D03*
X358800Y803600D03*
X368700Y803750D03*
X388250Y803300D03*
X385196Y779112D03*
X331300Y838500D03*
X402000Y844000D03*
X360100Y808080D03*
X371059Y903347D03*
X355622Y919857D03*
X380000Y920000D03*
X400000D03*
Y900000D03*
X368500Y865000D03*
X372000D03*
X379228Y874277D03*
X387250Y881000D03*
X351740Y880717D03*
X343749Y874298D03*
X351792Y885835D03*
X379270Y885897D03*
X387292D03*
X343770D03*
X360800Y858500D03*
X375200Y858250D03*
X343894Y880707D03*
X379372Y880728D03*
X335823Y940330D03*
X340000Y980000D03*
X360000D03*
X380000D03*
X400000D03*
Y960000D03*
X380000D03*
X340000D03*
X360000D03*
Y940000D03*
X380000D03*
X400000D03*
Y1060000D03*
X380000D03*
X400000Y1040000D03*
X380000D03*
X360000Y1060000D03*
X340000D03*
X360000Y1040000D03*
X340000D03*
Y1000000D03*
Y1020000D03*
X360000Y1000000D03*
Y1020000D03*
X380000Y1000000D03*
Y1020000D03*
X400000Y1000000D03*
Y1020000D03*
X360000Y1140000D03*
X340000D03*
X380000Y1100000D03*
X400000Y1080000D03*
X380000D03*
X360000Y1100000D03*
X340000D03*
X360000Y1080000D03*
X340000D03*
Y1160000D03*
X354228Y1164233D03*
X370000Y1212500D03*
Y1207000D03*
X375500D03*
X381000D03*
X375500Y1212500D03*
X381000D03*
X359000D03*
X364500D03*
Y1207000D03*
X359000D03*
X370000Y1201500D03*
X381000D03*
X375500D03*
X370000Y1190500D03*
Y1196000D03*
X375500D03*
Y1190500D03*
X381000D03*
Y1196000D03*
X364500Y1201500D03*
X365000Y1196000D03*
Y1190500D03*
X359000D03*
Y1196000D03*
Y1201500D03*
X337500Y1207750D03*
X331500Y1194500D03*
X371000Y1168000D03*
X367500D03*
X363500Y1165000D03*
X402000Y1202500D03*
X383750Y1150500D03*
X391765Y1157852D03*
X396750Y1181250D03*
X391758Y1145676D03*
X383757Y1145655D03*
X331500Y1190500D03*
X364300Y1174900D03*
X374200Y1174750D03*
X391900Y1150250D03*
X331300Y1210000D03*
X398750Y1188250D03*
X359175Y1179640D03*
X400000Y1280000D03*
Y1260000D03*
X339500Y1218250D03*
X370200Y1239700D03*
X368500Y1236500D03*
X372000D03*
X343749Y1245719D03*
X351771Y1252213D03*
X379249Y1245782D03*
X387208Y1252212D03*
X391500Y1218500D03*
X351750Y1257380D03*
X379270D03*
X387292Y1257360D03*
X343760Y1257381D03*
X365200Y1229800D03*
X400700Y1237500D03*
X375200Y1229750D03*
X343822Y1252222D03*
X379395Y1252274D03*
X400000Y1340000D03*
X380000D03*
Y1320000D03*
X400000D03*
X380000Y1300000D03*
X400000D03*
X360000Y1340000D03*
Y1320000D03*
X340000Y1340000D03*
X380000Y1420000D03*
Y1400000D03*
X400000Y1420000D03*
Y1400000D03*
Y1380000D03*
Y1360000D03*
X380000D03*
Y1380000D03*
X360000D03*
Y1360000D03*
X340000D03*
Y1380000D03*
X380000Y1500000D03*
X360000D03*
X340000Y1480000D03*
Y1460000D03*
X400000D03*
X380000Y1440000D03*
X400000D03*
X360000Y1560000D03*
X400000Y1540000D03*
X380000D03*
X360000D03*
Y1520000D03*
X380000D03*
X400000D03*
Y1580000D03*
X380000D03*
X348250Y1649000D03*
X356247Y1644123D03*
X348257Y1644132D03*
X356174Y1649291D03*
X334500Y1650000D03*
Y1665000D03*
X380000Y1660000D03*
X400000D03*
X359000Y1705500D03*
Y1700000D03*
Y1694500D03*
Y1689000D03*
X365000D03*
Y1694500D03*
X364500Y1700000D03*
Y1705500D03*
Y1711000D03*
X359000D03*
X381000D03*
X375500D03*
X381000Y1705500D03*
X375500D03*
X381000Y1694500D03*
Y1689000D03*
X375500D03*
Y1694500D03*
X370000D03*
Y1689000D03*
Y1705500D03*
Y1711000D03*
X381000Y1700000D03*
X375500D03*
X370000D03*
X402000Y1701000D03*
X339500Y1716750D03*
X337500Y1706250D03*
X331500Y1695000D03*
X368500Y1664000D03*
X372500Y1667000D03*
X376000D03*
X388750Y1673000D03*
X356238Y1655722D03*
X331500Y1691000D03*
X369100Y1673700D03*
X385250Y1673000D03*
X331500Y1708500D03*
X395500Y1690500D03*
X376890Y1678000D03*
X368500Y1768000D03*
X400000Y1760000D03*
X365400Y1734400D03*
X369000Y1734500D03*
X372500D03*
X393000Y1723500D03*
X351750Y1751000D03*
X343709Y1744187D03*
X376808Y1755434D03*
X373005D03*
X379000Y1736000D03*
X351750Y1755500D03*
X343750D03*
X383000Y1736300D03*
X365700Y1727700D03*
X383000Y1728700D03*
X375700Y1727750D03*
X343668Y1750741D03*
X379000Y1726000D03*
X400000Y1860000D03*
X380000D03*
X360000D03*
X340000D03*
Y1800000D03*
Y1840000D03*
X360000D03*
X380000D03*
X400000D03*
Y1820000D03*
X380000D03*
X360000D03*
X340000D03*
X360000Y1800000D03*
X400000D03*
X380000D03*
X400000Y1940000D03*
X380000D03*
X360000D03*
X340000D03*
Y1900000D03*
Y1920000D03*
X360000D03*
Y1900000D03*
X380000D03*
Y1920000D03*
X400000D03*
Y1900000D03*
X340000Y1880000D03*
X360000D03*
X380000D03*
X400000D03*
X340000Y1980000D03*
Y1960000D03*
X360000Y1980000D03*
Y1960000D03*
X380000Y1980000D03*
Y1960000D03*
X400000Y1980000D03*
Y1960000D03*
X392559Y1986626D03*
X372559D03*
X352559D03*
X332559D03*
X460000Y20000D03*
Y40000D03*
X420000Y20000D03*
Y40000D03*
X440000D03*
Y20000D03*
X470018Y5500D03*
X410018D03*
X430018D03*
X450018D03*
X460000Y100000D03*
X420000D03*
X440000D03*
X460000Y80000D03*
Y60000D03*
X440000D03*
Y80000D03*
X420000D03*
Y60000D03*
X460000Y120000D03*
X440000D03*
X420000D03*
Y180000D03*
X440000D03*
X460000D03*
Y140000D03*
Y160000D03*
X440000D03*
Y140000D03*
X420000D03*
Y160000D03*
Y200000D03*
X460000D03*
X440000D03*
X420000Y220000D03*
X440000D03*
X460000D03*
Y240000D03*
X440000D03*
X420000D03*
Y260000D03*
X440000D03*
X460000D03*
X440000Y280000D03*
X460000D03*
X440000Y320000D03*
X460000D03*
Y300000D03*
X405500Y277500D03*
X405000Y289000D03*
X440000Y400000D03*
X460000D03*
Y380000D03*
X440000D03*
Y360000D03*
X460000D03*
Y340000D03*
X440000D03*
X460000Y480000D03*
Y460000D03*
X440000Y480000D03*
Y460000D03*
Y440000D03*
X460000D03*
Y420000D03*
X440000D03*
X410550Y420500D03*
X420000Y520000D03*
Y540000D03*
X440000D03*
Y520000D03*
X460000D03*
Y500000D03*
X420000D03*
Y620000D03*
X440000Y600000D03*
X460000Y580000D03*
X420000Y600000D03*
X440000Y580000D03*
X420000Y560000D03*
Y700000D03*
X460000Y660000D03*
Y680000D03*
Y700000D03*
X420000Y680000D03*
Y660000D03*
Y720000D03*
Y740000D03*
X460000Y720000D03*
Y760000D03*
X420000D03*
Y840000D03*
X440000D03*
X460000D03*
Y820000D03*
Y800000D03*
Y780000D03*
X420000D03*
X414281Y820751D03*
X421000Y812750D03*
X425890Y820729D03*
X425891Y812750D03*
X404000Y840500D03*
X420722Y820627D03*
X420000Y920000D03*
X440000D03*
X460000D03*
Y900000D03*
X440000D03*
X420000D03*
Y880000D03*
X460000D03*
X440000D03*
X420000Y860000D03*
X440000D03*
X460000D03*
X410550Y850500D03*
X420000Y980000D03*
X440000D03*
X460000D03*
Y960000D03*
X440000D03*
X420000D03*
Y940000D03*
X440000D03*
X460000D03*
X420000Y1060000D03*
X440000Y1040000D03*
X420000D03*
Y1000000D03*
Y1020000D03*
X440000Y1000000D03*
Y1020000D03*
X460000D03*
Y1000000D03*
X440000Y1120000D03*
X460000D03*
Y1080000D03*
X420000Y1200000D03*
X440000D03*
X460000D03*
Y1160000D03*
Y1180000D03*
X440000Y1160000D03*
Y1180000D03*
X420000Y1160000D03*
Y1180000D03*
X405500Y1192000D03*
X420000Y1280000D03*
Y1240000D03*
X440000D03*
X460000D03*
Y1260000D03*
X440000D03*
X420000D03*
X460000Y1280000D03*
X440000D03*
X420743Y1215266D03*
X414274Y1223246D03*
X408300Y1237500D03*
X425500Y1215250D03*
Y1223250D03*
X420763Y1223185D03*
X420000Y1340000D03*
Y1320000D03*
X440000D03*
Y1340000D03*
X460000D03*
Y1320000D03*
X440000Y1300000D03*
X420000D03*
X460000D03*
X440000Y1420000D03*
X420000D03*
Y1400000D03*
Y1380000D03*
Y1360000D03*
X440000Y1400000D03*
Y1360000D03*
Y1380000D03*
X460000D03*
Y1360000D03*
Y1420000D03*
Y1400000D03*
X440000Y1500000D03*
X420000Y1480000D03*
X440000D03*
Y1460000D03*
X420000D03*
Y1440000D03*
X440000D03*
X460000Y1500000D03*
Y1480000D03*
Y1460000D03*
Y1440000D03*
X420000Y1540000D03*
X460000Y1520000D03*
Y1580000D03*
X440000D03*
X420000D03*
Y1700000D03*
Y1680000D03*
Y1660000D03*
X440000Y1680000D03*
X460000D03*
Y1660000D03*
X421000Y1713750D03*
X414299Y1721750D03*
X425879Y1721724D03*
X425500Y1713750D03*
X420732Y1721757D03*
X420000Y1760000D03*
X406500Y1736500D03*
X440000Y1780000D03*
Y1760000D03*
X460000D03*
Y1780000D03*
X450000Y1803500D03*
X440000Y1860000D03*
X420000D03*
Y1840000D03*
X440000D03*
X420000Y1820000D03*
X460000Y1840000D03*
Y1860000D03*
Y1940000D03*
X440000D03*
X420000D03*
Y1900000D03*
Y1920000D03*
X440000D03*
Y1900000D03*
X460000Y1920000D03*
Y1900000D03*
X420000Y1880000D03*
X440000D03*
X460000D03*
X420000Y1980000D03*
Y1960000D03*
X440000Y1980000D03*
Y1960000D03*
X460000Y1980000D03*
Y1960000D03*
X472559Y1986626D03*
X452559D03*
X432559D03*
X412559D03*
X500000Y40000D03*
X480000D03*
X520000D03*
X530018Y5500D03*
X510018D03*
X490018D03*
X500000Y20000D03*
X480000D03*
X520000D03*
X540000Y40000D03*
Y20000D03*
Y100000D03*
X520000D03*
X500000D03*
X480000D03*
Y120000D03*
X500000D03*
X520000D03*
X480000Y60000D03*
Y80000D03*
X500000D03*
Y60000D03*
X520000D03*
Y80000D03*
X540000Y120000D03*
Y80000D03*
Y60000D03*
X480000Y140000D03*
Y160000D03*
X500000D03*
Y140000D03*
X520000D03*
Y160000D03*
Y180000D03*
X500000D03*
X480000D03*
X540000Y160000D03*
Y140000D03*
Y180000D03*
X520000Y260000D03*
X500000D03*
X520000Y240000D03*
X480000D03*
X500000D03*
Y220000D03*
X480000D03*
Y200000D03*
X500000D03*
X520000D03*
Y220000D03*
X540000Y260000D03*
Y220000D03*
Y240000D03*
Y200000D03*
X500000Y280000D03*
X520000D03*
X480000D03*
Y300000D03*
X500000D03*
X520000D03*
Y320000D03*
X500000D03*
X480000D03*
X540000Y280000D03*
Y300000D03*
Y320000D03*
X500000Y400000D03*
X520000D03*
Y380000D03*
X540000Y400000D03*
Y380000D03*
Y360000D03*
Y340000D03*
X480000Y400000D03*
Y340000D03*
X500000D03*
X520000D03*
Y360000D03*
X500000D03*
X480000D03*
Y380000D03*
Y440000D03*
X500000D03*
X480000Y420000D03*
X500000D03*
X520000D03*
X540000D03*
X520000Y480000D03*
X500000D03*
X480000D03*
Y460000D03*
X500000D03*
X520000D03*
Y440000D03*
X540000Y460000D03*
Y440000D03*
X500000Y500000D03*
X480000D03*
X520000Y520000D03*
X500000Y540000D03*
X540000D03*
X520000Y560000D03*
X540000D03*
Y580000D03*
X500000D03*
Y600000D03*
X520000D03*
X540000D03*
X520000Y580000D03*
X480000Y560000D03*
X540000Y700000D03*
X520000D03*
X500000D03*
X480000D03*
X540000Y680000D03*
X520000D03*
X500000D03*
X480000D03*
X540000Y660000D03*
X520000D03*
X500000D03*
X480000D03*
Y640000D03*
X500000D03*
X520000D03*
X540000D03*
X520000Y720000D03*
X500000D03*
X480000D03*
X540000Y740000D03*
X480000Y760000D03*
X500000D03*
X520000D03*
X540000D03*
X520000Y780000D03*
X500000D03*
X480000D03*
Y800000D03*
X500000D03*
X520000D03*
X480000Y820000D03*
X500000D03*
X520000D03*
X480000Y840000D03*
X500000D03*
X520000D03*
X540000D03*
Y780000D03*
Y800000D03*
Y820000D03*
X520000Y900000D03*
Y920000D03*
X500000D03*
X480000D03*
X520000Y860000D03*
X500000D03*
X480000D03*
Y880000D03*
X500000D03*
X520000D03*
X480000Y900000D03*
X500000D03*
X540000Y920000D03*
Y860000D03*
Y880000D03*
Y900000D03*
X520000Y980000D03*
X500000D03*
X480000D03*
X520000Y940000D03*
X500000D03*
X480000D03*
Y960000D03*
X500000D03*
X520000D03*
X540000Y980000D03*
Y940000D03*
Y960000D03*
X520000Y1060000D03*
X500000D03*
X480000D03*
Y1000000D03*
X500000Y1040000D03*
X520000D03*
X540000Y1060000D03*
Y1040000D03*
X480000Y1080000D03*
X500000D03*
X520000D03*
Y1120000D03*
X500000D03*
X480000D03*
X540000D03*
Y1100000D03*
X520000Y1200000D03*
X500000D03*
X480000D03*
Y1180000D03*
Y1160000D03*
X500000Y1180000D03*
Y1160000D03*
X520000Y1180000D03*
Y1160000D03*
X540000Y1180000D03*
Y1160000D03*
Y1200000D03*
X480000Y1280000D03*
X500000D03*
X520000D03*
X480000Y1260000D03*
X500000D03*
X520000D03*
X500000Y1240000D03*
X480000D03*
X540000Y1280000D03*
Y1220000D03*
X500000Y1340000D03*
X520000D03*
X480000D03*
Y1320000D03*
X500000D03*
X520000D03*
X480000Y1300000D03*
X500000D03*
X520000D03*
X540000Y1340000D03*
Y1320000D03*
Y1300000D03*
X520000Y1420000D03*
X500000D03*
X480000D03*
X520000Y1380000D03*
Y1400000D03*
X500000Y1380000D03*
Y1400000D03*
X480000Y1380000D03*
Y1400000D03*
X500000Y1360000D03*
X520000D03*
X480000D03*
X540000Y1420000D03*
Y1380000D03*
Y1400000D03*
Y1360000D03*
X520000Y1500000D03*
X500000D03*
X480000D03*
X520000Y1440000D03*
Y1460000D03*
Y1480000D03*
X500000Y1440000D03*
Y1460000D03*
Y1480000D03*
X480000Y1440000D03*
Y1460000D03*
Y1480000D03*
X540000Y1500000D03*
Y1440000D03*
Y1460000D03*
Y1480000D03*
X500000Y1560000D03*
X480000Y1520000D03*
X500000D03*
X520000D03*
X540000D03*
X547659Y1560537D03*
X542159D03*
Y1566037D03*
X547659D03*
X480000Y1580000D03*
X540000Y1680000D03*
X520000D03*
X500000D03*
X480000D03*
Y1700000D03*
Y1660000D03*
Y1720000D03*
X500000D03*
X520000D03*
Y1700000D03*
X500000D03*
X520000Y1660000D03*
X500000D03*
X540000Y1700000D03*
Y1720000D03*
Y1660000D03*
Y1780000D03*
X520000Y1760000D03*
X480000Y1780000D03*
X500000D03*
X520000D03*
X480000Y1760000D03*
X500000D03*
X520000Y1740000D03*
X500000D03*
X480000D03*
X540000Y1760000D03*
Y1740000D03*
Y1820000D03*
Y1840000D03*
Y1860000D03*
X520000D03*
X480000D03*
X500000Y1840000D03*
X520000D03*
X500000Y1820000D03*
X480000D03*
X520000D03*
X540000Y1940000D03*
X500000D03*
X520000D03*
X480000D03*
X520000Y1920000D03*
X500000D03*
X480000D03*
X520000Y1900000D03*
X500000D03*
X480000D03*
Y1880000D03*
X500000D03*
X520000D03*
X540000Y1900000D03*
Y1880000D03*
Y1920000D03*
X492559Y1986626D03*
X512559D03*
X532559D03*
X520000Y1960000D03*
Y1980000D03*
X500000Y1960000D03*
Y1980000D03*
X480000Y1960000D03*
Y1980000D03*
X540000Y1960000D03*
Y1980000D03*
X580000Y40000D03*
X560000D03*
X600000D03*
X590018Y5500D03*
X570018D03*
X550018D03*
X580000Y20000D03*
X560000D03*
X600000D03*
X620000Y40000D03*
X610018Y5500D03*
X620000Y20000D03*
Y100000D03*
X600000D03*
X580000D03*
X560000D03*
Y120000D03*
X580000D03*
X600000D03*
X560000Y60000D03*
Y80000D03*
X580000D03*
Y60000D03*
X600000D03*
Y80000D03*
X620000Y120000D03*
Y80000D03*
Y60000D03*
X560000Y140000D03*
Y160000D03*
X580000D03*
Y140000D03*
X600000D03*
Y160000D03*
Y180000D03*
X580000D03*
X560000D03*
X620000Y160000D03*
Y140000D03*
Y180000D03*
X580000Y260000D03*
X600000D03*
X620000D03*
X560000D03*
X600000Y200000D03*
Y220000D03*
X580000D03*
Y200000D03*
X560000D03*
Y220000D03*
Y240000D03*
X580000D03*
X600000D03*
X620000D03*
Y220000D03*
Y200000D03*
X560000Y320000D03*
X580000D03*
X600000D03*
X620000D03*
X560000Y300000D03*
X580000D03*
X600000D03*
X620000D03*
X580000Y280000D03*
X600000D03*
X620000D03*
X560000D03*
X620000Y400000D03*
X600000D03*
X580000D03*
X560000D03*
Y380000D03*
X580000D03*
X600000D03*
X620000D03*
X560000Y360000D03*
X580000D03*
X600000D03*
X620000D03*
X560000Y340000D03*
X580000D03*
X600000D03*
X620000D03*
X600000Y480000D03*
X620000D03*
Y460000D03*
X580000Y440000D03*
X560000D03*
X620000Y420000D03*
X600000D03*
X580000D03*
X560000D03*
Y460000D03*
X620000Y520000D03*
X600000D03*
X580000D03*
Y500000D03*
X600000Y540000D03*
Y500000D03*
X620000D03*
X580000Y540000D03*
X560000D03*
X620000D03*
Y560000D03*
X580000D03*
X600000D03*
X560000D03*
Y580000D03*
X600000D03*
X620000Y600000D03*
X600000D03*
X580000D03*
Y580000D03*
X620000D03*
Y640000D03*
X600000D03*
X580000D03*
X560000D03*
X620000Y700000D03*
X600000D03*
X580000D03*
X560000D03*
X620000Y680000D03*
X600000D03*
X580000D03*
X560000D03*
X620000Y660000D03*
X600000D03*
X580000D03*
X560000D03*
Y740000D03*
X580000D03*
X600000D03*
X620000D03*
X580000Y760000D03*
X600000D03*
X620000D03*
X560000D03*
X580000Y780000D03*
X600000D03*
X620000D03*
X580000Y800000D03*
X600000D03*
X620000D03*
X580000Y820000D03*
X600000D03*
X620000D03*
X560000Y840000D03*
X580000D03*
X600000D03*
X560000Y780000D03*
Y800000D03*
X620000Y840000D03*
X600000Y920000D03*
X580000D03*
X560000D03*
X600000Y860000D03*
X580000D03*
X560000D03*
Y900000D03*
Y880000D03*
X580000D03*
Y900000D03*
X600000D03*
Y880000D03*
X620000Y920000D03*
Y880000D03*
Y900000D03*
Y860000D03*
X600000Y980000D03*
X580000D03*
X560000D03*
X580000Y940000D03*
X560000D03*
Y960000D03*
X580000D03*
X600000D03*
Y940000D03*
X620000D03*
Y960000D03*
Y980000D03*
X600000Y1060000D03*
X580000D03*
X560000D03*
Y1040000D03*
X580000D03*
X600000D03*
X620000D03*
Y1060000D03*
X560000Y1100000D03*
X580000D03*
X600000D03*
Y1120000D03*
X580000D03*
X560000D03*
X620000D03*
Y1100000D03*
X560000Y1180000D03*
X580000D03*
Y1160000D03*
X600000Y1180000D03*
Y1160000D03*
Y1200000D03*
X580000D03*
X560000D03*
X620000D03*
Y1160000D03*
Y1180000D03*
X580000Y1260000D03*
Y1240000D03*
X560000D03*
X600000Y1220000D03*
X580000D03*
X560000D03*
X600000Y1260000D03*
Y1240000D03*
X620000Y1280000D03*
Y1220000D03*
Y1240000D03*
Y1260000D03*
X560000Y1340000D03*
X580000D03*
X600000D03*
X560000Y1320000D03*
X580000D03*
X560000Y1300000D03*
X620000D03*
X600000Y1420000D03*
X580000D03*
X560000D03*
X600000Y1400000D03*
X580000Y1380000D03*
Y1400000D03*
X560000Y1380000D03*
Y1400000D03*
X580000Y1360000D03*
X600000D03*
X620000Y1420000D03*
Y1400000D03*
Y1380000D03*
Y1360000D03*
X600000Y1500000D03*
X580000D03*
X560000D03*
X600000Y1440000D03*
Y1460000D03*
Y1480000D03*
X580000Y1440000D03*
Y1460000D03*
Y1480000D03*
X560000Y1440000D03*
Y1460000D03*
Y1480000D03*
X620000Y1500000D03*
Y1480000D03*
Y1460000D03*
Y1440000D03*
X560000Y1520000D03*
X580000D03*
X620000Y1680000D03*
X560000D03*
X580000D03*
X600000D03*
Y1700000D03*
Y1720000D03*
X580000D03*
Y1700000D03*
X560000D03*
Y1720000D03*
X600000Y1660000D03*
X580000D03*
X560000D03*
X620000Y1700000D03*
Y1720000D03*
Y1660000D03*
Y1780000D03*
X600000D03*
X580000D03*
X560000D03*
X620000Y1760000D03*
X600000D03*
X580000D03*
X560000D03*
X620000Y1740000D03*
X600000D03*
X580000D03*
X560000D03*
Y1840000D03*
Y1860000D03*
X620000Y1800000D03*
X600000D03*
X580000D03*
X560000D03*
X620000Y1840000D03*
X600000D03*
X580000D03*
X620000Y1860000D03*
X600000D03*
X580000D03*
X560000Y1940000D03*
X580000D03*
X600000D03*
X620000D03*
X560000Y1880000D03*
X620000D03*
X600000D03*
X580000D03*
X620000Y1900000D03*
X600000D03*
X580000D03*
X620000Y1920000D03*
X600000D03*
X580000D03*
X560000D03*
Y1900000D03*
X620000Y1960000D03*
X600000D03*
X580000D03*
X552559Y1986626D03*
X572559D03*
X592559D03*
X600000Y1980000D03*
X580000D03*
X560000D03*
Y1960000D03*
X612559Y1986626D03*
X620000Y1980000D03*
X660000Y40000D03*
X640000D03*
X670018Y5500D03*
X650018D03*
X630018D03*
X660000Y20000D03*
X640000D03*
X680000D03*
Y40000D03*
X690018Y5500D03*
X680000Y100000D03*
X660000D03*
X640000D03*
Y120000D03*
X660000D03*
X640000Y60000D03*
Y80000D03*
X660000D03*
Y60000D03*
X680000Y120000D03*
Y60000D03*
Y80000D03*
X640000Y140000D03*
Y160000D03*
X660000D03*
Y140000D03*
Y180000D03*
X640000D03*
X680000Y140000D03*
Y160000D03*
Y180000D03*
X660000Y260000D03*
X640000D03*
Y240000D03*
X660000D03*
Y220000D03*
Y200000D03*
X640000Y220000D03*
Y200000D03*
X680000Y260000D03*
Y240000D03*
Y220000D03*
Y200000D03*
X640000Y320000D03*
X660000D03*
X680000D03*
X640000Y300000D03*
X660000D03*
X680000D03*
X640000Y280000D03*
X660000D03*
X680000D03*
X640000Y400000D03*
Y380000D03*
X660000D03*
X640000Y360000D03*
X660000D03*
X680000D03*
X640000Y340000D03*
X660000D03*
X680000D03*
Y480000D03*
Y460000D03*
Y440000D03*
X640000Y480000D03*
X660000D03*
Y460000D03*
X640000D03*
X660000Y440000D03*
X640000D03*
X680000Y420000D03*
X660000Y520000D03*
X640000D03*
X680000D03*
Y500000D03*
X640000D03*
X660000D03*
X640000Y540000D03*
X660000D03*
X680000D03*
X663000Y535500D03*
X680000Y560000D03*
X660000D03*
X640000D03*
X680000Y600000D03*
X660000D03*
X640000D03*
Y580000D03*
X660000D03*
X680000D03*
Y660000D03*
Y680000D03*
X640000Y640000D03*
Y700000D03*
X660000Y680000D03*
X640000D03*
X660000Y660000D03*
X640000D03*
X660000Y640000D03*
X680000D03*
X661500Y650500D03*
X640000Y720000D03*
X660000D03*
X680000D03*
X640000Y740000D03*
X660000D03*
X680000D03*
X640000Y760000D03*
X660000D03*
X680000D03*
X640000Y780000D03*
X660000D03*
X680000D03*
X640000Y800000D03*
X660000D03*
X680000D03*
X640000Y820000D03*
X660000D03*
X680000D03*
X640000Y840000D03*
X660000D03*
X680000D03*
X662000Y826600D03*
X640000Y920000D03*
X660000D03*
X640000Y900000D03*
X660000D03*
X640000Y880000D03*
X660000D03*
X640000Y860000D03*
X660000D03*
X680000Y920000D03*
Y900000D03*
Y880000D03*
Y860000D03*
X640000Y940000D03*
Y960000D03*
X660000D03*
Y980000D03*
X640000D03*
X680000D03*
Y960000D03*
X665000Y937000D03*
X660000Y1040000D03*
X640000D03*
Y1060000D03*
X680000Y1040000D03*
X660000Y1053500D03*
X640000Y1100000D03*
Y1120000D03*
X660000D03*
Y1100000D03*
X680000D03*
Y1120000D03*
Y1080000D03*
X640000Y1200000D03*
X660000D03*
Y1160000D03*
X640000D03*
Y1180000D03*
X680000Y1160000D03*
Y1200000D03*
X662000Y1183500D03*
X640000Y1280000D03*
X660000D03*
Y1220000D03*
X640000D03*
Y1240000D03*
X660000D03*
X640000Y1260000D03*
X660000D03*
X680000Y1240000D03*
Y1260000D03*
Y1280000D03*
Y1220000D03*
X660000Y1340000D03*
X640000Y1300000D03*
X660000D03*
Y1320000D03*
X640000D03*
X680000Y1340000D03*
Y1300000D03*
Y1320000D03*
X657000Y1331500D03*
X660000Y1420000D03*
X640000D03*
Y1400000D03*
X660000D03*
X640000Y1380000D03*
X680000Y1420000D03*
Y1360000D03*
X660000Y1500000D03*
X640000D03*
X660000Y1480000D03*
X640000D03*
Y1460000D03*
Y1440000D03*
X660000D03*
X680000Y1500000D03*
Y1480000D03*
Y1440000D03*
X662000Y1459000D03*
X634200Y1561200D03*
Y1565700D03*
X639700Y1561200D03*
Y1565700D03*
X646200Y1561200D03*
Y1565700D03*
X651700Y1561200D03*
Y1565700D03*
X640000Y1680000D03*
X660000D03*
X680000D03*
Y1720000D03*
X640000Y1700000D03*
X660000D03*
Y1720000D03*
X640000D03*
Y1660000D03*
X660000D03*
X680000Y1780000D03*
X660000D03*
X640000D03*
X680000Y1760000D03*
X660000D03*
X640000D03*
X680000Y1740000D03*
X660000D03*
X640000D03*
X680000Y1820000D03*
X660000D03*
X680000Y1800000D03*
X660000D03*
X640000D03*
X680000Y1860000D03*
X660000Y1840000D03*
X640000D03*
Y1860000D03*
X660000D03*
X680000Y1880000D03*
Y1900000D03*
Y1920000D03*
X660000Y1880000D03*
X640000D03*
X660000Y1900000D03*
X640000D03*
X660000Y1920000D03*
X640000D03*
Y1940000D03*
X660000D03*
X680000Y1960000D03*
X660000D03*
X640000D03*
X632559Y1986626D03*
X652559D03*
X672559D03*
X660000Y1980000D03*
X640000D03*
X680000D03*
X692559Y1986626D03*
X700000Y20000D03*
X740000Y40000D03*
X750018Y5500D03*
X730018D03*
X710018D03*
X740000Y20000D03*
X720000D03*
X760000Y40000D03*
Y20000D03*
X700000Y120000D03*
X720000D03*
X740000D03*
X700000Y80000D03*
Y60000D03*
Y100000D03*
X720000D03*
Y60000D03*
X740000D03*
Y80000D03*
X720000D03*
X740000Y100000D03*
X760000Y120000D03*
Y100000D03*
Y80000D03*
Y60000D03*
X700000Y180000D03*
X740000D03*
X720000D03*
Y140000D03*
Y160000D03*
X760000D03*
X740000D03*
X700000D03*
Y140000D03*
X740000D03*
X760000D03*
Y180000D03*
X700000Y260000D03*
Y240000D03*
Y220000D03*
Y200000D03*
X720000Y260000D03*
Y240000D03*
Y220000D03*
Y200000D03*
X740000Y260000D03*
Y200000D03*
Y220000D03*
Y240000D03*
X760000Y260000D03*
Y200000D03*
Y220000D03*
Y240000D03*
Y320000D03*
X700000D03*
Y300000D03*
Y280000D03*
X720000Y320000D03*
Y300000D03*
Y280000D03*
X740000D03*
Y300000D03*
X760000Y280000D03*
X740000Y400000D03*
X720000D03*
X700000D03*
X740000Y380000D03*
X720000D03*
X760000Y400000D03*
Y360000D03*
Y380000D03*
Y460000D03*
Y480000D03*
X740000D03*
X720000D03*
X700000D03*
Y420000D03*
X720000D03*
X740000D03*
Y440000D03*
X720000D03*
X700000D03*
Y460000D03*
X720000D03*
X740000D03*
X760000Y420000D03*
Y440000D03*
X720000Y520000D03*
X700000D03*
X740000Y500000D03*
X720000D03*
X740000Y520000D03*
X700000Y500000D03*
Y540000D03*
X740000D03*
X720000D03*
X760000D03*
Y520000D03*
Y500000D03*
Y560000D03*
X720000D03*
X740000D03*
X700000D03*
X740000Y600000D03*
Y580000D03*
X720000D03*
X740000Y620000D03*
X720000D03*
X700000Y580000D03*
Y600000D03*
X720000D03*
X760000Y620000D03*
Y600000D03*
Y580000D03*
Y680000D03*
Y640000D03*
X740000D03*
Y680000D03*
X720000D03*
X700000D03*
Y660000D03*
X720000D03*
X740000D03*
X700000Y640000D03*
X720000D03*
X700000Y720000D03*
X720000D03*
X740000D03*
Y760000D03*
X720000D03*
X700000D03*
Y740000D03*
X720000D03*
X740000D03*
X760000Y760000D03*
Y740000D03*
Y720000D03*
X740000Y840000D03*
X700000D03*
X720000D03*
X740000Y800000D03*
X720000D03*
X700000D03*
Y820000D03*
X720000D03*
X740000D03*
X700000Y780000D03*
X720000D03*
X740000D03*
X760000Y840000D03*
Y800000D03*
Y820000D03*
Y780000D03*
X740000Y920000D03*
X700000D03*
X720000D03*
X740000Y900000D03*
Y880000D03*
Y860000D03*
X700000Y900000D03*
X720000D03*
X700000Y880000D03*
X720000D03*
X700000Y860000D03*
X720000D03*
X760000Y920000D03*
Y900000D03*
Y880000D03*
Y860000D03*
X700000Y980000D03*
X720000D03*
X740000D03*
X700000Y960000D03*
X720000D03*
X740000D03*
X760000Y980000D03*
Y960000D03*
X740000Y1040000D03*
X720000D03*
X700000D03*
X760000D03*
X700000Y1120000D03*
Y1100000D03*
X720000Y1120000D03*
X740000D03*
Y1080000D03*
X700000D03*
X760000Y1120000D03*
X740000Y1160000D03*
X720000D03*
X700000D03*
Y1200000D03*
X720000D03*
X740000D03*
X760000Y1160000D03*
Y1200000D03*
X700000Y1240000D03*
X740000Y1260000D03*
X720000D03*
X700000D03*
X740000Y1280000D03*
X720000D03*
X700000D03*
Y1220000D03*
X720000D03*
X740000D03*
Y1240000D03*
X720000D03*
X760000D03*
Y1260000D03*
Y1280000D03*
Y1220000D03*
X740000Y1340000D03*
X720000D03*
X700000D03*
X740000Y1300000D03*
X720000D03*
X700000D03*
Y1320000D03*
X740000D03*
X720000D03*
X760000Y1340000D03*
Y1300000D03*
Y1320000D03*
X740000Y1420000D03*
X720000D03*
X740000Y1380000D03*
Y1360000D03*
X720000Y1380000D03*
Y1360000D03*
X700000Y1380000D03*
Y1360000D03*
X760000Y1420000D03*
Y1380000D03*
Y1360000D03*
X700000Y1500000D03*
X740000Y1440000D03*
X720000D03*
X700000D03*
X740000Y1480000D03*
X720000D03*
X700000D03*
X760000Y1440000D03*
Y1480000D03*
X740000Y1520000D03*
X720000D03*
X760000D03*
X700000Y1680000D03*
X740000Y1700000D03*
X720000D03*
Y1720000D03*
X740000D03*
Y1680000D03*
X720000D03*
X760000Y1720000D03*
X753500Y1662000D03*
Y1666500D03*
X759000Y1662000D03*
Y1666500D03*
X765500Y1662000D03*
Y1666500D03*
X700000Y1780000D03*
Y1760000D03*
Y1740000D03*
X720000Y1780000D03*
X740000Y1740000D03*
X760000Y1780000D03*
Y1740000D03*
X758000Y1756000D03*
X759700Y1817500D03*
X700000Y1820000D03*
Y1800000D03*
Y1860000D03*
X720000D03*
X740000D03*
X720000Y1800000D03*
X740000D03*
Y1820000D03*
X720000D03*
X759700Y1837500D03*
X720000Y1880000D03*
X740000Y1900000D03*
Y1880000D03*
X700000D03*
Y1900000D03*
Y1920000D03*
X720000Y1940000D03*
Y1900000D03*
Y1920000D03*
X700000Y1940000D03*
X760000Y1880000D03*
Y1940000D03*
X728700Y1933100D03*
X720000Y1960000D03*
X700000D03*
X720000Y1980000D03*
X700000D03*
X712559Y1986626D03*
X732559D03*
X740000Y1960000D03*
Y1980000D03*
X752559Y1986626D03*
X759900Y1959200D03*
X760000Y1980000D03*
X755995Y1968282D03*
X800000Y40000D03*
X820000D03*
X840000D03*
X780000D03*
X810018Y5500D03*
X790018D03*
X770018D03*
X780000Y20000D03*
X800000D03*
X820000D03*
X830018Y5500D03*
X840000Y20000D03*
X800000Y120000D03*
X820000D03*
X840000D03*
X800000Y100000D03*
X820000D03*
X840000D03*
X800000Y80000D03*
X820000D03*
X840000D03*
X800000Y60000D03*
X820000D03*
X840000D03*
X780000Y120000D03*
Y60000D03*
Y80000D03*
Y100000D03*
Y160000D03*
X840000Y140000D03*
X820000D03*
X800000D03*
X816000Y187000D03*
X780000Y140000D03*
Y180000D03*
X828500Y171000D03*
X840000Y174250D03*
X820500Y171000D03*
X792343Y193599D03*
X832500Y171000D03*
X824500D03*
X816500D03*
X820000Y260000D03*
X780000Y200000D03*
Y220000D03*
Y240000D03*
X800000Y220000D03*
Y240000D03*
X820000Y220000D03*
X840000Y240000D03*
X828000Y203000D03*
X792343Y197402D03*
X780000Y300000D03*
X800000Y280000D03*
Y340000D03*
X780000D03*
Y380000D03*
Y360000D03*
Y400000D03*
X820000D03*
X800000D03*
Y380000D03*
Y360000D03*
X840000Y400000D03*
X824335Y365915D03*
X815375Y362750D03*
X836500Y362500D03*
X833000D03*
X840000Y366000D03*
Y362500D03*
X833000Y366000D03*
X836500D03*
X813350Y369250D03*
X780000Y440000D03*
Y420000D03*
Y460000D03*
X800000Y480000D03*
X820000Y420000D03*
Y440000D03*
Y460000D03*
X800000D03*
Y440000D03*
Y420000D03*
X820000Y480000D03*
X780000D03*
X840000D03*
Y420000D03*
Y440000D03*
Y460000D03*
X780000Y540000D03*
X800000D03*
X820000D03*
X780000Y500000D03*
X820000D03*
Y520000D03*
X800000Y500000D03*
Y520000D03*
X780000D03*
X840000Y500000D03*
Y520000D03*
Y540000D03*
X780000Y580000D03*
Y560000D03*
X800000Y600000D03*
Y580000D03*
Y560000D03*
X780000Y620000D03*
X800000D03*
X820000D03*
X780000Y600000D03*
X820000Y580000D03*
Y560000D03*
Y600000D03*
X840000Y620000D03*
Y580000D03*
Y560000D03*
Y600000D03*
X820000Y700000D03*
X780000D03*
X778400Y659800D03*
X800000Y640000D03*
X780000D03*
X820000Y660000D03*
X798400Y659800D03*
X840000Y640000D03*
Y680000D03*
Y660000D03*
Y700000D03*
X782500Y648000D03*
X820000Y720000D03*
X800000Y760000D03*
X780000D03*
Y740000D03*
X800000D03*
Y720000D03*
X780000D03*
X840000D03*
X824335Y771415D03*
X815375Y768250D03*
X840000Y771500D03*
X833000D03*
X836500D03*
X840000Y768000D03*
X836500D03*
X833000D03*
X780000Y840000D03*
X800000D03*
X820000D03*
Y820000D03*
X780000Y800000D03*
Y780000D03*
X800000D03*
X840000Y840000D03*
Y800000D03*
Y820000D03*
X780000Y920000D03*
X800000D03*
X820000D03*
X780000Y900000D03*
X800000D03*
X820000D03*
X780000Y880000D03*
X800000D03*
X820000D03*
X780000Y860000D03*
X800000D03*
X820000D03*
X840000Y920000D03*
Y860000D03*
Y880000D03*
Y900000D03*
X780000Y980000D03*
X800000D03*
X820000D03*
X780000Y960000D03*
X800000D03*
X820000D03*
X840000D03*
Y980000D03*
X800000Y1060000D03*
X820000D03*
X780000D03*
X820000Y1040000D03*
X840000Y1060000D03*
Y1040000D03*
X780000Y1120000D03*
X800000D03*
Y1080000D03*
Y1100000D03*
X820000Y1120000D03*
X800000Y1200000D03*
X820000D03*
X780000Y1160000D03*
X800000D03*
X780000Y1200000D03*
X840000D03*
X824335Y1176915D03*
X815375Y1173750D03*
X836500Y1177000D03*
X833000D03*
X840000D03*
X820000Y1220000D03*
Y1240000D03*
X800000D03*
X780000D03*
X820000Y1260000D03*
X800000D03*
X780000D03*
X820000Y1280000D03*
X800000D03*
X780000D03*
Y1220000D03*
X800000D03*
X840000Y1280000D03*
Y1220000D03*
Y1240000D03*
Y1260000D03*
X820000Y1340000D03*
X800000D03*
X780000D03*
X820000Y1300000D03*
X800000D03*
X780000D03*
Y1320000D03*
X820000D03*
X800000D03*
X840000Y1340000D03*
Y1300000D03*
Y1320000D03*
X820000Y1420000D03*
X800000D03*
X780000D03*
X820000Y1380000D03*
Y1360000D03*
X800000Y1380000D03*
Y1360000D03*
X780000Y1380000D03*
Y1360000D03*
X840000Y1420000D03*
Y1360000D03*
Y1380000D03*
X820000Y1440000D03*
X800000D03*
X780000D03*
X820000Y1480000D03*
X800000D03*
X780000D03*
X840000Y1440000D03*
Y1480000D03*
X800000Y1560000D03*
X780000Y1520000D03*
X840000Y1640000D03*
Y1600000D03*
X824335Y1582415D03*
X816625Y1579250D03*
X840000Y1582500D03*
X833000D03*
X836500D03*
X840000Y1579000D03*
X836500D03*
X833000D03*
X813000Y1585750D03*
X808500Y1621500D03*
X814000D03*
Y1626000D03*
X808500D03*
X814000Y1630500D03*
X808500D03*
X820000Y1680000D03*
X829388Y1695500D03*
X825388D03*
X833388D03*
X837388D03*
X840000Y1680000D03*
Y1660000D03*
X771000Y1662000D03*
Y1666500D03*
X780000Y1780000D03*
X800000D03*
Y1740000D03*
X780000D03*
X795500Y1755000D03*
X825388Y1739500D03*
X829388D03*
X833388D03*
X837388D03*
X837500Y1785000D03*
X829500D03*
X819000D03*
X815000D03*
X816000Y1801000D03*
X780000Y1800000D03*
X800000D03*
X780000Y1840000D03*
X800000Y1820000D03*
X820000D03*
X828000Y1862000D03*
X827500Y1817000D03*
X834750Y1823285D03*
X819000Y1839000D03*
X800000Y1920000D03*
X820000D03*
X780000D03*
X796339Y1937007D03*
X820000Y1980000D03*
X772559Y1986626D03*
X792559D03*
X812559D03*
X769239Y1955776D03*
X780000Y1980000D03*
X800000D03*
X823400Y1973400D03*
X827900D03*
X835900Y1973500D03*
X839400D03*
X832559Y1986626D03*
X840000Y1980000D03*
X799205Y1960532D03*
X774989Y1955708D03*
X780214Y1953257D03*
X796339Y1940507D03*
X804239Y1953307D03*
Y1956807D03*
X800739D03*
Y1953307D03*
X797239D03*
Y1956807D03*
X785239Y1960907D03*
X860000Y40000D03*
X880000D03*
X890018Y5500D03*
X870018D03*
X850018D03*
X880000Y20000D03*
X860000D03*
X900000Y40000D03*
X910018Y5500D03*
X900000Y20000D03*
X860000Y120000D03*
X880000D03*
X860000Y100000D03*
X880000D03*
X860000Y80000D03*
X880000D03*
X860000Y60000D03*
X880000D03*
X900000Y120000D03*
Y60000D03*
Y100000D03*
Y80000D03*
X860000Y140000D03*
X908493Y136513D03*
X880000Y180000D03*
X869250Y144750D03*
X885993Y134893D03*
X885531Y164804D03*
X896441Y147203D03*
X844000Y190000D03*
X866961Y162539D03*
X896547Y150803D03*
X890469Y164804D03*
X864975Y148875D03*
X863441Y219890D03*
X876441Y262165D03*
Y255866D03*
X863307Y264102D03*
X860000Y260000D03*
X876441Y246417D03*
Y236968D03*
Y230669D03*
Y221220D03*
Y211771D03*
X863441Y213102D03*
X860000Y240000D03*
X899941Y233917D03*
Y218917D03*
Y203917D03*
X908654Y231105D03*
X904838D03*
X872500Y241500D03*
X876500Y251000D03*
X901441Y244842D03*
X908346Y235394D03*
X905146D03*
X872941Y223745D03*
Y228145D03*
X867441Y214896D03*
Y218096D03*
Y265290D03*
X901600Y249800D03*
X863307Y269678D03*
X863441Y288972D03*
X863346Y301768D03*
X860100Y336500D03*
X873600Y332200D03*
X860100Y333000D03*
X876441Y318858D03*
Y309409D03*
Y299960D03*
Y290511D03*
Y281063D03*
Y271614D03*
X863346Y307602D03*
X863441Y282602D03*
X901500Y312500D03*
X899941Y283917D03*
Y278917D03*
X856200Y337300D03*
X844050D03*
X872941Y274138D03*
Y278538D03*
Y293036D03*
Y297436D03*
Y311934D03*
Y316334D03*
X867441Y268490D03*
Y284187D03*
Y287387D03*
Y303085D03*
Y306285D03*
X899941Y308917D03*
X865000Y371000D03*
X868500D03*
X876000D03*
X872500D03*
X879600Y385200D03*
X860000Y400000D03*
X880000D03*
X900000D03*
X899900Y382300D03*
X850966Y370025D03*
X843500Y366000D03*
Y362500D03*
X880000Y480000D03*
X860000D03*
X880000Y420000D03*
X860000D03*
X880000Y440000D03*
X860000D03*
X880000Y460000D03*
X860000D03*
X900000Y480000D03*
Y420000D03*
Y440000D03*
Y460000D03*
X907493Y542025D03*
X880000Y500000D03*
X860000D03*
X880000Y520000D03*
X860000D03*
X900000Y500000D03*
Y520000D03*
X872875Y535275D03*
X891250Y537500D03*
X895547Y552715D03*
X857735Y553465D03*
X895547Y556315D03*
X865125Y544000D03*
X863441Y625402D03*
X876441Y626732D03*
Y617283D03*
X863441Y618614D03*
X860000Y580000D03*
Y560000D03*
X880000Y580000D03*
Y600000D03*
X860000D03*
X899941Y624429D03*
Y609429D03*
X900000Y600000D03*
X883781Y564519D03*
X872941Y629257D03*
X867441Y620408D03*
Y623608D03*
X888719Y564519D03*
X863441Y694484D03*
X863287Y669690D03*
X876441Y661378D03*
Y651929D03*
Y642480D03*
Y636181D03*
X863287Y675114D03*
X863441Y688114D03*
X876441Y696023D03*
Y686575D03*
Y677126D03*
Y667677D03*
X899941Y684429D03*
Y639429D03*
X908654Y636613D03*
X904838D03*
X899941Y689429D03*
X868500Y654000D03*
X876500Y648000D03*
X901441Y650354D03*
X908346Y640906D03*
X905146D03*
X872941Y633657D03*
Y679650D03*
Y684050D03*
Y698548D03*
Y702948D03*
X867441Y670802D03*
Y674002D03*
Y689699D03*
Y692899D03*
X901200Y655100D03*
X863397Y713280D03*
X859500Y741800D03*
X876441Y724370D03*
Y714921D03*
Y705472D03*
X863397Y707114D03*
X873400Y738400D03*
X859500Y738300D03*
X901500Y718000D03*
X856100Y743300D03*
X850966Y775525D03*
X843500Y771500D03*
Y768000D03*
X846200Y743300D03*
X872941Y717446D03*
Y721846D03*
X867441Y708597D03*
Y711797D03*
X899941Y714429D03*
X860000Y840000D03*
X880000D03*
X864500Y776500D03*
X868000D03*
X872000D03*
X875500D03*
X860000Y800000D03*
X880000D03*
X860000Y820000D03*
X880000D03*
X900000Y840000D03*
Y800000D03*
Y820000D03*
X860000Y920000D03*
X880000D03*
X860000Y860000D03*
X880000D03*
X860000Y880000D03*
X880000D03*
X860000Y900000D03*
X880000D03*
X900000Y920000D03*
Y860000D03*
Y880000D03*
Y900000D03*
X907493Y947537D03*
X860000Y980000D03*
X886517Y945917D03*
X872875Y940925D03*
X883781Y970031D03*
X895547Y958227D03*
X857623Y958977D03*
X895547Y961827D03*
X888719Y970031D03*
X865125Y949600D03*
X863441Y1030914D03*
X876441Y1066890D03*
Y1057441D03*
Y1047992D03*
Y1041693D03*
Y1032244D03*
Y1022795D03*
X863441Y1024126D03*
X880000Y1000000D03*
X860000Y1040000D03*
X899941Y1044941D03*
Y1029941D03*
Y1014941D03*
X908654Y1042129D03*
X904838D03*
X900000Y1000000D03*
Y1040000D03*
Y1020000D03*
X868500Y1059500D03*
X901441Y1055866D03*
X876500Y1053500D03*
X908346Y1046418D03*
X905146D03*
X872941Y1034769D03*
Y1039169D03*
X867441Y1025920D03*
Y1029120D03*
X901300Y1060700D03*
X863346Y1112792D03*
X863441Y1099996D03*
X863308Y1080702D03*
X876441Y1129882D03*
Y1120433D03*
Y1110984D03*
Y1101535D03*
Y1092087D03*
Y1082638D03*
Y1073189D03*
X863308Y1075126D03*
X863441Y1093626D03*
X863346Y1118626D03*
X899941Y1094941D03*
Y1089941D03*
X900000Y1080000D03*
X901500Y1123500D03*
X872941Y1085162D03*
Y1089562D03*
Y1104060D03*
Y1108460D03*
Y1122958D03*
Y1127358D03*
X867441Y1076314D03*
Y1079514D03*
Y1095211D03*
Y1098411D03*
Y1114109D03*
Y1117309D03*
X899941Y1119941D03*
X859500Y1147600D03*
X874200Y1144000D03*
X859500Y1144100D03*
X864000Y1181900D03*
X867500D03*
X872200D03*
X875700D03*
X860000Y1200000D03*
X880000D03*
X900000D03*
X854500Y1148700D03*
X850600Y1181025D03*
X843500Y1177000D03*
X844600Y1148700D03*
X860000Y1280000D03*
X880000D03*
X860000Y1220000D03*
Y1240000D03*
Y1260000D03*
X880000Y1220000D03*
Y1240000D03*
Y1260000D03*
X900000Y1280000D03*
Y1220000D03*
Y1240000D03*
Y1260000D03*
X907493Y1353048D03*
X880000Y1340000D03*
X860000D03*
Y1300000D03*
Y1320000D03*
X880000D03*
Y1300000D03*
X900000Y1320000D03*
Y1300000D03*
X872875Y1346488D03*
X891250Y1348500D03*
X865125Y1346488D03*
X876441Y1428307D03*
X863441Y1429638D03*
X860000Y1420000D03*
Y1380000D03*
X899941Y1420453D03*
X883219Y1373504D03*
X895647Y1363738D03*
X857688Y1364488D03*
X895647Y1367338D03*
X887438Y1373374D03*
X863286Y1480714D03*
X863441Y1436426D03*
X876441Y1478701D03*
Y1472402D03*
Y1462953D03*
Y1453504D03*
Y1447205D03*
Y1437756D03*
X860000Y1440000D03*
X876441Y1497599D03*
Y1488150D03*
X863286Y1486138D03*
X863441Y1499138D03*
X899941Y1450453D03*
Y1435453D03*
X908654Y1447641D03*
X904838D03*
X899941Y1500453D03*
Y1495453D03*
X868500Y1465000D03*
X901441Y1461378D03*
X876500Y1459000D03*
X908346Y1451930D03*
X905146D03*
X872941Y1440281D03*
Y1444681D03*
Y1490674D03*
Y1495074D03*
X867441Y1431432D03*
Y1434632D03*
Y1481826D03*
Y1485026D03*
Y1500723D03*
X901400Y1466100D03*
X863347Y1518304D03*
X863441Y1505508D03*
X859500Y1553200D03*
X876441Y1535394D03*
Y1525945D03*
Y1516496D03*
Y1507047D03*
X863347Y1524138D03*
X873300Y1549100D03*
X859500Y1549700D03*
X901500Y1529000D03*
X855500Y1554300D03*
X845600D03*
X872941Y1509572D03*
Y1513972D03*
Y1528470D03*
Y1532870D03*
X867441Y1503923D03*
Y1519621D03*
Y1522821D03*
X899941Y1525453D03*
X860000Y1640000D03*
Y1580000D03*
X865500Y1589000D03*
X869000D03*
X873000D03*
X876500D03*
X880000Y1599000D03*
X900000Y1600000D03*
X850966Y1586525D03*
X843500Y1582500D03*
Y1579000D03*
X891500Y1712000D03*
X895500D03*
Y1708000D03*
X841388Y1695500D03*
X873962Y1672000D03*
Y1676500D03*
Y1681500D03*
Y1685500D03*
X860000Y1660000D03*
X906000Y1713500D03*
X885750Y1701500D03*
X891500Y1708000D03*
X891000Y1720000D03*
X901500Y1681500D03*
X881353Y1650749D03*
X877853D03*
Y1654249D03*
X881353D03*
X896500Y1681000D03*
X859500Y1696000D03*
X886600Y1756100D03*
X872875Y1751600D03*
X906500Y1734100D03*
X907493Y1758560D03*
X898500Y1734000D03*
X910500Y1734600D03*
X895547Y1769250D03*
X883781Y1781054D03*
X895547Y1772850D03*
X888719Y1781054D03*
X865125Y1751800D03*
X902500Y1734000D03*
X910500Y1724700D03*
X863441Y1841938D03*
X876441Y1859016D03*
Y1852717D03*
X860000Y1860000D03*
X876441Y1843268D03*
Y1833819D03*
X863441Y1835150D03*
X899941Y1855965D03*
X908654Y1853153D03*
X904838D03*
X899941Y1840965D03*
Y1825965D03*
X876000Y1864000D03*
X901441Y1866890D03*
X908346Y1857442D03*
X905146D03*
X872941Y1845793D03*
Y1850193D03*
X867441Y1836944D03*
Y1840144D03*
X863346Y1923816D03*
X863441Y1911020D03*
X863287Y1886226D03*
X876441Y1912559D03*
Y1903111D03*
Y1893662D03*
Y1884213D03*
Y1877914D03*
Y1868465D03*
X863287Y1891650D03*
X863441Y1904650D03*
X860000Y1880000D03*
X876441Y1931457D03*
Y1922008D03*
X863346Y1929650D03*
X901500Y1934500D03*
X899941Y1905965D03*
Y1900965D03*
X867500Y1870000D03*
X872941Y1896186D03*
Y1900586D03*
Y1915084D03*
Y1919484D03*
Y1933982D03*
Y1938382D03*
X867441Y1887338D03*
Y1890538D03*
Y1906235D03*
Y1909435D03*
Y1925133D03*
Y1928333D03*
X899941Y1930965D03*
X901200Y1871600D03*
X876441Y1940906D03*
X843500Y1973500D03*
X847000D03*
X852559Y1986626D03*
X872559D03*
X896546Y1986566D03*
X860000Y1980000D03*
X912559Y1986626D03*
X844800Y1949700D03*
X858800Y1951300D03*
X879500Y1970000D03*
X880000Y1955500D03*
X862000Y1969900D03*
Y1960500D03*
X844700Y1945200D03*
X960000Y40000D03*
X940000D03*
X920000D03*
X950018Y5500D03*
X930018D03*
X920000Y20000D03*
X940000D03*
X960000D03*
X980000Y40000D03*
X970018Y5500D03*
X980000Y20000D03*
X960000Y120000D03*
X940000D03*
X920000D03*
Y60000D03*
X940000D03*
X960000D03*
X920000Y100000D03*
X940000D03*
X960000D03*
Y80000D03*
X940000D03*
X920000D03*
X980000Y120000D03*
Y60000D03*
Y100000D03*
Y80000D03*
X960000Y140000D03*
X940000D03*
X960000Y160000D03*
X940000D03*
Y180000D03*
X960000D03*
X980000D03*
X926347Y155500D03*
Y160000D03*
Y164453D03*
X921400Y235002D03*
Y245200D03*
X940000Y200000D03*
X960000D03*
Y220000D03*
X940000D03*
Y240000D03*
X960000D03*
Y260000D03*
X940000D03*
X980000Y240000D03*
Y260000D03*
Y200000D03*
Y220000D03*
X918846Y238501D03*
Y241701D03*
X940000Y280000D03*
X920000D03*
X960000D03*
X920000Y300000D03*
X940000D03*
X960000D03*
X920000Y320000D03*
X940000D03*
X960000D03*
X980000Y280000D03*
Y300000D03*
Y320000D03*
X960000Y400000D03*
X940000D03*
X920000D03*
X960000Y340000D03*
X940000D03*
X920000D03*
Y360000D03*
X940000D03*
X960000D03*
Y380000D03*
X940000D03*
X920000D03*
X980000Y400000D03*
Y340000D03*
Y360000D03*
Y380000D03*
X920000Y480000D03*
X940000D03*
X960000D03*
X920000Y420000D03*
X940000D03*
X960000D03*
X920000Y440000D03*
X940000D03*
X960000D03*
X920000Y460000D03*
X940000D03*
X960000D03*
X980000Y480000D03*
Y420000D03*
Y440000D03*
Y460000D03*
X920000Y500000D03*
X940000D03*
X960000D03*
X920000Y520000D03*
X940000D03*
X960000D03*
Y540000D03*
X980000Y500000D03*
Y520000D03*
Y540000D03*
X940000Y620000D03*
X960000D03*
Y560000D03*
Y580000D03*
Y600000D03*
X940000Y580000D03*
Y600000D03*
X920000Y580000D03*
Y600000D03*
X980000Y620000D03*
Y560000D03*
Y580000D03*
Y600000D03*
X926365Y561000D03*
Y569965D03*
Y565500D03*
X919000Y639715D03*
X920000Y700000D03*
X919000Y651511D03*
X940000Y640000D03*
X960000D03*
X920000Y680000D03*
X940000D03*
X960000D03*
Y660000D03*
X940000D03*
X920000D03*
X940000Y700000D03*
X960000D03*
X980000Y640000D03*
Y660000D03*
Y700000D03*
X918846Y644013D03*
Y647213D03*
X940000Y760000D03*
X960000D03*
X920000D03*
Y740000D03*
Y720000D03*
X940000D03*
X960000D03*
X940000Y740000D03*
X960000D03*
X980000Y760000D03*
Y720000D03*
Y740000D03*
X940000Y840000D03*
X960000D03*
X920000D03*
X940000Y780000D03*
X960000D03*
X940000Y800000D03*
X960000D03*
X940000Y820000D03*
X960000D03*
X920000Y800000D03*
Y820000D03*
Y780000D03*
X980000Y840000D03*
Y780000D03*
Y800000D03*
Y820000D03*
X940000Y920000D03*
X960000D03*
X920000D03*
X940000Y860000D03*
X960000D03*
X940000Y880000D03*
X960000D03*
X940000Y900000D03*
X960000D03*
X920000Y860000D03*
Y880000D03*
Y900000D03*
X980000Y920000D03*
Y860000D03*
Y880000D03*
Y900000D03*
X960000Y980000D03*
Y940000D03*
X940000D03*
X960000Y960000D03*
X980000Y980000D03*
Y940000D03*
Y960000D03*
X926477Y966500D03*
Y971000D03*
Y975477D03*
X922900Y1048050D03*
Y1054200D03*
X920000Y1060000D03*
X940000D03*
X960000D03*
Y1000000D03*
X940000D03*
X920000D03*
Y1020000D03*
X940000D03*
X960000D03*
Y1040000D03*
X940000D03*
X920000D03*
X980000Y1000000D03*
Y1020000D03*
Y1040000D03*
X918846Y1049525D03*
Y1052725D03*
X940000Y1140000D03*
X960000D03*
X920000Y1080000D03*
X940000D03*
X960000D03*
Y1100000D03*
X940000D03*
X920000Y1120000D03*
X940000D03*
X960000D03*
X920000Y1140000D03*
X980000D03*
Y1100000D03*
X979962Y1075211D03*
X980000Y1120000D03*
X923000Y1160200D03*
X940000Y1160000D03*
X960000D03*
Y1180000D03*
X940000D03*
X923000Y1180200D03*
X960000Y1200000D03*
X940000D03*
X920000D03*
X980000Y1160000D03*
Y1180000D03*
Y1200000D03*
X960000Y1280000D03*
X940000D03*
X920000D03*
X960000Y1220000D03*
X940000D03*
X960000Y1240000D03*
X940000D03*
X960000Y1260000D03*
X940000D03*
X920000Y1220000D03*
Y1240000D03*
Y1260000D03*
X980000Y1220000D03*
Y1240000D03*
Y1260000D03*
Y1280000D03*
X960000Y1340000D03*
X940000D03*
X920000D03*
X960000Y1300000D03*
X940000D03*
X960000Y1320000D03*
X940000D03*
X920000Y1300000D03*
Y1320000D03*
X980000Y1340000D03*
Y1300000D03*
Y1320000D03*
X981700Y1409000D03*
X954300Y1412600D03*
X960000Y1360000D03*
Y1380000D03*
Y1400000D03*
X940000D03*
X920000D03*
X963500Y1409000D03*
X973000D03*
X968000D03*
X977500D03*
X980000Y1360000D03*
Y1380000D03*
Y1400000D03*
X926300Y1372000D03*
Y1380988D03*
Y1376500D03*
X919000Y1450734D03*
Y1462540D03*
X920000Y1480000D03*
Y1440000D03*
X918846Y1455037D03*
Y1458237D03*
X920000Y1520000D03*
Y1540000D03*
X923800Y1559300D03*
X923500Y1579800D03*
X920000Y1600000D03*
X959000Y1631000D03*
X943500Y1646989D03*
X973000Y1641500D03*
X931000Y1659000D03*
X960000Y1700000D03*
Y1720000D03*
X933000Y1704000D03*
X951500Y1658000D03*
X952000Y1678000D03*
X980000Y1700000D03*
Y1720000D03*
X963500Y1675000D03*
Y1657000D03*
X959000D03*
Y1675000D03*
X926500Y1660000D03*
X941000Y1653000D03*
X934825Y1682285D03*
X947000Y1654500D03*
X915250Y1687500D03*
X919250Y1711500D03*
X960000Y1740000D03*
Y1760000D03*
X940000D03*
X933000Y1736500D03*
X925500Y1738000D03*
X960000Y1780000D03*
X980000D03*
Y1740000D03*
Y1760000D03*
X916500Y1729500D03*
X926400Y1777500D03*
Y1782000D03*
Y1786500D03*
X921900Y1722400D03*
X919000Y1856251D03*
X960000Y1860000D03*
X940000D03*
X960000Y1800000D03*
X940000D03*
X920000D03*
X940000Y1820000D03*
X960000D03*
X940000Y1840000D03*
X960000D03*
X920000D03*
X980000Y1860000D03*
Y1800000D03*
Y1820000D03*
Y1840000D03*
X918846Y1860549D03*
Y1863749D03*
X920000Y1920000D03*
X940000D03*
X960000D03*
Y1940000D03*
X940000D03*
X920000D03*
X919000Y1868047D03*
X960000Y1880000D03*
X940000D03*
X920000D03*
X960000Y1900000D03*
X940000D03*
X920000D03*
X980000Y1920000D03*
Y1940000D03*
X980018Y1897856D03*
X932559Y1986626D03*
X952559D03*
X960000Y1960000D03*
X940000D03*
X920000D03*
Y1980000D03*
X940000D03*
X960000D03*
X972559Y1986626D03*
X980000Y1960000D03*
Y1980000D03*
X1031902Y43616D03*
X1020000Y40000D03*
X1000000D03*
X1031902Y23616D03*
X1030018Y5500D03*
X1010018D03*
X990018D03*
X1000000Y20000D03*
X1020000D03*
Y120000D03*
X1000000D03*
X1031902Y63616D03*
Y103616D03*
Y83616D03*
X1000000Y60000D03*
X1020000D03*
X1000000Y100000D03*
X1020000D03*
Y80000D03*
X1000000D03*
X1031902Y143616D03*
Y123616D03*
Y163616D03*
X1020000Y140000D03*
Y160000D03*
Y180000D03*
X1031902Y183616D03*
X1000000Y240000D03*
X1020000D03*
X1031902Y263616D03*
X1020000Y260000D03*
X1000000D03*
X1031902Y223616D03*
Y203616D03*
Y243616D03*
X1000000Y200000D03*
X1020000D03*
Y220000D03*
X1000000D03*
X1031902Y303616D03*
Y283616D03*
Y323616D03*
X1000000Y280000D03*
X1020000D03*
X1000000Y300000D03*
X1020000D03*
X1000000Y320000D03*
X1020000D03*
X1031902Y403616D03*
X1020000Y400000D03*
X1000000D03*
X1031902Y383616D03*
Y363616D03*
Y343616D03*
X1020000Y340000D03*
X1000000D03*
Y360000D03*
X1020000D03*
Y380000D03*
X1000000D03*
X1031902Y483616D03*
X1000000Y480000D03*
X1020000D03*
X1031902Y443616D03*
Y423616D03*
Y463616D03*
X1000000Y420000D03*
X1020000D03*
X1000000Y440000D03*
X1020000D03*
X1000000Y460000D03*
X1020000D03*
X1031902Y523616D03*
Y503616D03*
Y543616D03*
X1000000Y500000D03*
X1020000D03*
X1000000Y520000D03*
X1020000D03*
X1000000Y540000D03*
X1020000D03*
X1031902Y623616D03*
X1000000Y620000D03*
X1020000D03*
X1031902Y603616D03*
Y583616D03*
Y563616D03*
X1020000Y560000D03*
X1000000D03*
X1020000Y580000D03*
X1000000D03*
X1020000Y600000D03*
X1000000D03*
X1031902Y683616D03*
Y663616D03*
Y643616D03*
X1000000Y640000D03*
X1020000D03*
Y660000D03*
Y680000D03*
Y700000D03*
X1000000Y740000D03*
X1020000D03*
X1000000Y760000D03*
X1020000D03*
X1031902Y763616D03*
Y743616D03*
Y723616D03*
Y703616D03*
X1000000Y720000D03*
X1020000D03*
X1031902Y843616D03*
X1000000Y840000D03*
X1020000D03*
X1031902Y823616D03*
Y803616D03*
Y783616D03*
X1000000Y780000D03*
X1020000D03*
X1000000Y800000D03*
X1020000D03*
X1000000Y820000D03*
X1020000D03*
X1000000Y920000D03*
X1020000D03*
X1031902Y903616D03*
Y883616D03*
Y863616D03*
X1000000Y860000D03*
X1020000D03*
X1000000Y880000D03*
X1020000D03*
X1000000Y900000D03*
X1020000D03*
X1031902Y983616D03*
X1000000Y980000D03*
X1020000D03*
X1031902Y963616D03*
Y943616D03*
Y923616D03*
X1020000Y940000D03*
X1000000D03*
Y960000D03*
X1020000D03*
X1031902Y1063616D03*
X1020000Y1060000D03*
X1031902Y1043616D03*
Y1023616D03*
Y1003616D03*
X1020000Y1000000D03*
X1000000D03*
Y1020000D03*
X1020000D03*
Y1040000D03*
X1000000D03*
X1031902Y1123616D03*
X1000000Y1140000D03*
X1020000D03*
X1031902Y1103616D03*
Y1083616D03*
X1020000Y1080000D03*
Y1100000D03*
X999922Y1102598D03*
X1000000Y1120000D03*
X1020000D03*
X1031902Y1143616D03*
Y1183616D03*
Y1163616D03*
X1000000Y1160000D03*
X1020000D03*
Y1180000D03*
X1000000D03*
X1031902Y1203616D03*
X1020000Y1200000D03*
X1000000D03*
Y1220000D03*
X1020000Y1240000D03*
X1000000D03*
X1020000Y1260000D03*
X1000000D03*
X1031902Y1283616D03*
X1020000Y1280000D03*
X1000000D03*
X1031902Y1263616D03*
Y1243616D03*
Y1223616D03*
X1020000Y1220000D03*
X1031902Y1343616D03*
X1020000Y1340000D03*
X1000000D03*
X1031902Y1323616D03*
Y1303616D03*
X1020000Y1300000D03*
X1000000D03*
X1020000Y1320000D03*
X1000000D03*
X986200Y1409000D03*
X994600Y1414100D03*
X990300Y1412500D03*
X1031902Y1363616D03*
Y1383616D03*
X1020000Y1360000D03*
X1000000D03*
Y1380000D03*
X1020000D03*
Y1400000D03*
X1000000D03*
X994898Y1646102D03*
X992500Y1636000D03*
X991602Y1622500D03*
X1000000Y1700000D03*
X1020000Y1720000D03*
X1000000D03*
X995102Y1676102D03*
X995000Y1656102D03*
Y1666102D03*
X1031902Y1785969D03*
X1000000Y1780000D03*
X1020000D03*
X1031902Y1745969D03*
Y1725969D03*
Y1765969D03*
X1000000Y1740000D03*
X1020000D03*
Y1760000D03*
X1000000D03*
X1031902Y1865969D03*
Y1845969D03*
X1020000Y1860000D03*
X1000000D03*
X1031902Y1805969D03*
Y1825969D03*
X1020000Y1800000D03*
X1000000D03*
Y1820000D03*
X1020000D03*
X1000000Y1840000D03*
X1020000D03*
X1031902Y1925969D03*
X999469Y1923465D03*
X1020000Y1920000D03*
Y1940000D03*
X1000000D03*
X1031902Y1885969D03*
Y1905969D03*
X1020000Y1880000D03*
Y1900000D03*
X1031902Y1965969D03*
Y1945969D03*
X992559Y1986626D03*
X1012559D03*
X1031902Y1985969D03*
X1020000Y1960000D03*
X1000000D03*
Y1980000D03*
X1020000D03*
X1271996Y417379D03*
G54D21*
G01X-106883Y-224955D02*
Y-304955D01*
G01Y-260455D02*
X1019417D01*
G01X-106883Y-304955D02*
X1019417D01*
G01X-110883Y-208955D02*
G02I-12000J0D01*
G01X-116033D02*
G02I-6850J0D01*
G01X-122883Y-224955D02*
Y-192955D01*
G01X-106883Y-208955D02*
X-138883D01*
G01X-106883Y-224955D02*
X1019417D01*
G01X231917D02*
Y-304955D01*
G01X369417Y-224955D02*
Y-304955D01*
G01X484417Y-224955D02*
Y-304955D01*
G01X651917Y-224955D02*
Y-304955D01*
G01X821917Y-224955D02*
Y-304955D01*
G01X1019417Y-224955D02*
Y-304955D01*
G01X1047417Y-208955D02*
G02I-12000J0D01*
G01X1042267D02*
G02I-6850J0D01*
G01X1035417Y-224955D02*
Y-192955D01*
G01X1051417Y-208955D02*
X1019417D01*
G54D12*
X33465Y281496D03*
X21654Y1922835D03*
X133858Y17717D03*
X275591Y279528D03*
Y685030D03*
Y1088573D03*
Y1903534D03*
X998031Y163376D03*
Y686998D03*
Y1082667D03*
Y1903534D03*
X1271996Y276879D03*
G54D22*
G01X-90900Y-277455D02*
Y-294955D01*
X-82166D01*
G01X-69033Y-283289D02*
Y-294955D01*
G01Y-278622D02*
X-69470Y-278330D01*
Y-277747D01*
X-69033Y-277455D01*
X-68596Y-277747D01*
Y-278330D01*
X-69033Y-278622D01*
G01X-54590Y-299330D02*
X-53061Y-300497D01*
X-51315Y-300788D01*
X-49787Y-300497D01*
X-48476Y-299039D01*
X-47603Y-296997D01*
Y-283289D01*
G01Y-285622D02*
X-48476Y-284455D01*
X-49787Y-283580D01*
X-51315Y-283289D01*
X-53061Y-283872D01*
X-54153Y-285038D01*
X-55027Y-287080D01*
X-55463Y-289122D01*
X-55245Y-290872D01*
X-54371Y-292914D01*
X-53061Y-294372D01*
X-51315Y-294955D01*
X-50005Y-294663D01*
X-48476Y-293497D01*
X-47603Y-292331D01*
G01X-37745Y-294955D02*
Y-277455D01*
G01Y-285913D02*
X-36653Y-284455D01*
X-35561Y-283580D01*
X-33815Y-283289D01*
X-32505Y-283580D01*
X-30976Y-284747D01*
X-30321Y-286497D01*
Y-294955D01*
G01X-16533Y-277455D02*
Y-294955D01*
G01X-19590Y-283289D02*
X-13476D01*
G01X-2745Y-294955D02*
Y-283289D01*
G01Y-286205D02*
X-1871Y-284747D01*
X-561Y-283580D01*
X1185Y-283289D01*
X2713Y-283580D01*
X4024Y-284747D01*
X4679Y-286788D01*
Y-294955D01*
G01X18467Y-283289D02*
Y-294955D01*
G01Y-278622D02*
X18030Y-278330D01*
Y-277747D01*
X18467Y-277455D01*
X18904Y-277747D01*
Y-278330D01*
X18467Y-278622D01*
G01X32255Y-294955D02*
Y-283289D01*
G01Y-286205D02*
X33129Y-284747D01*
X34439Y-283580D01*
X36185Y-283289D01*
X37713Y-283580D01*
X39024Y-284747D01*
X39679Y-286788D01*
Y-294955D01*
G01X50410Y-299330D02*
X51939Y-300497D01*
X53685Y-300788D01*
X55213Y-300497D01*
X56524Y-299039D01*
X57397Y-296997D01*
Y-283289D01*
G01Y-285622D02*
X56524Y-284455D01*
X55213Y-283580D01*
X53685Y-283289D01*
X51939Y-283872D01*
X50847Y-285038D01*
X49973Y-287080D01*
X49537Y-289122D01*
X49755Y-290872D01*
X50629Y-292914D01*
X51939Y-294372D01*
X53685Y-294955D01*
X54995Y-294663D01*
X56524Y-293497D01*
X57397Y-292331D01*
G01X84100Y-294955D02*
Y-277455D01*
X89340D01*
X91087Y-278330D01*
X92397Y-280372D01*
X92834Y-282705D01*
X92397Y-285038D01*
X91305Y-286788D01*
X89340Y-287664D01*
X84100D01*
G01X101164Y-294955D02*
Y-277455D01*
X105530D01*
X107277Y-278330D01*
X108587Y-279497D01*
X109679Y-281246D01*
X110552Y-283289D01*
X110770Y-286205D01*
X110552Y-289122D01*
X109679Y-291164D01*
X108587Y-292914D01*
X107277Y-294080D01*
X105530Y-294955D01*
X101164D01*
G01X119100D02*
Y-277455D01*
X124340D01*
X126087Y-278330D01*
X127397Y-280372D01*
X127834Y-282705D01*
X127397Y-285038D01*
X126305Y-286788D01*
X124340Y-287664D01*
X119100D01*
G01X142713Y-285622D02*
X143587Y-284747D01*
X144242Y-283289D01*
X144679Y-281246D01*
X144242Y-279497D01*
X143369Y-278330D01*
X141840Y-277455D01*
X135945D01*
Y-294955D01*
X143150D01*
X144679Y-293789D01*
X145552Y-292038D01*
X145989Y-289997D01*
X145552Y-287955D01*
X144242Y-286205D01*
X142713Y-285622D01*
X135945D01*
G01X171600Y-294955D02*
Y-277455D01*
X176840D01*
X178587Y-278330D01*
X179897Y-280372D01*
X180334Y-282705D01*
X179897Y-285038D01*
X178805Y-286788D01*
X176840Y-287664D01*
X171600D01*
G01X188008Y-277455D02*
X193467Y-294955D01*
X198926Y-277455D01*
G01X210967D02*
Y-294955D01*
G01X205945Y-277455D02*
X215989D01*
G01X21540Y-249955D02*
Y-232455D01*
X27217Y-247038D01*
X32894Y-232455D01*
Y-249955D01*
G01X44717D02*
X43407Y-249663D01*
X42097Y-248497D01*
X41223Y-246455D01*
X40787Y-244122D01*
X41223Y-241788D01*
X42097Y-239747D01*
X43407Y-238580D01*
X44717Y-238289D01*
X46027Y-238580D01*
X47337Y-239747D01*
X48210Y-241788D01*
X48429Y-244122D01*
X48210Y-246455D01*
X47337Y-248497D01*
X46027Y-249663D01*
X44717Y-249955D01*
G01X66147Y-232455D02*
Y-249955D01*
G01Y-247331D02*
X65274Y-248789D01*
X63963Y-249663D01*
X62435Y-249955D01*
X60689Y-249372D01*
X59379Y-247914D01*
X58505Y-246164D01*
X58287Y-244122D01*
X58505Y-242080D01*
X59379Y-240330D01*
X60689Y-238872D01*
X62435Y-238289D01*
X63963Y-238580D01*
X65055Y-239164D01*
X66147Y-240330D01*
G01X76442Y-242080D02*
X83429D01*
X82774Y-240038D01*
X81682Y-238872D01*
X80154Y-238289D01*
X78625Y-238580D01*
X77315Y-239455D01*
X76442Y-241497D01*
X76005Y-243247D01*
Y-244997D01*
X76442Y-246747D01*
X77534Y-248497D01*
X78844Y-249663D01*
X80372Y-249955D01*
X81900Y-249372D01*
X83429Y-247622D01*
G01X97217Y-249955D02*
Y-232455D01*
G01X39370Y278851D02*
Y281496D01*
G03X27559I-5906J0D01*
G01Y278851D01*
G02X25809Y273902I-7873J0D01*
G03X41120I7655J-6187D01*
G02X39370Y278851I6123J4949D01*
G01X27559Y1920190D02*
Y1922835D01*
G03X15748I-5906J0D01*
G01Y1920190D01*
G02X13998Y1915241I-7873J0D01*
G03X29309I7656J-6187D01*
G02X27559Y1920190I6123J4949D01*
G01X27604Y1920184D02*
X33459Y1911041D01*
G01X31564Y1916782D02*
X27604Y1920184D01*
X29037Y1915164D01*
X31564Y1916782D01*
G01X71698Y18647D02*
X61622Y28637D01*
G01X67091Y21102D02*
X71698Y18647D01*
X69204Y23233D01*
X67091Y21102D01*
G01X70685Y18647D02*
X74985D01*
G02Y15447I0J-1600D01*
G01X70685D01*
G02Y18647I0J1600D01*
G01X72017Y188675D02*
X62402Y178464D01*
G01X69681Y184007D02*
X72017Y188675D01*
X67497Y186063D01*
X69681Y184007D01*
G01X70685Y191875D02*
X74985D01*
G02Y188675I0J-1600D01*
G01X70685D01*
G02Y191875I0J1600D01*
G01X39415Y278845D02*
X45270Y269702D01*
G01X43375Y275443D02*
X39415Y278845D01*
X40848Y273825D01*
X43375Y275443D01*
G01X71698Y424159D02*
X61622Y434149D01*
G01X67091Y426614D02*
X71698Y424159D01*
X69204Y428745D01*
X67091Y426614D01*
G01X70685Y424159D02*
X74985D01*
G02Y420959I0J-1600D01*
G01X70685D01*
G02Y424159I0J1600D01*
G01X72017Y594187D02*
X62402Y583976D01*
G01X69681Y589519D02*
X72017Y594187D01*
X67497Y591575D01*
X69681Y589519D01*
G01X70685Y597387D02*
X74985D01*
G02Y594187I0J-1600D01*
G01X70685D01*
G02Y597387I0J1600D01*
G01X71698Y829671D02*
X61622Y839661D01*
G01X67091Y832126D02*
X71698Y829671D01*
X69204Y834257D01*
X67091Y832126D01*
G01X70685Y829671D02*
X74985D01*
G02Y826471I0J-1600D01*
G01X70685D01*
G02Y829671I0J1600D01*
G01X72017Y999699D02*
X62402Y989488D01*
G01X69681Y995031D02*
X72017Y999699D01*
X67497Y997087D01*
X69681Y995031D01*
G01X70685Y1002899D02*
X74985D01*
G02Y999699I0J-1600D01*
G01X70685D01*
G02Y1002899I0J1600D01*
G01X71698Y1235183D02*
X61622Y1245173D01*
G01X67091Y1237638D02*
X71698Y1235183D01*
X69204Y1239769D01*
X67091Y1237638D01*
G01X70685Y1235183D02*
X74985D01*
G02Y1231983I0J-1600D01*
G01X70685D01*
G02Y1235183I0J1600D01*
G01X72017Y1405211D02*
X62402Y1395000D01*
G01X69681Y1400543D02*
X72017Y1405211D01*
X67497Y1402599D01*
X69681Y1400543D01*
G01X70685Y1408411D02*
X74985D01*
G02Y1405211I0J-1600D01*
G01X70685D01*
G02Y1408411I0J1600D01*
G01X71698Y1640695D02*
X61622Y1650685D01*
G01X67091Y1643150D02*
X71698Y1640695D01*
X69204Y1645281D01*
X67091Y1643150D01*
G01X70685Y1640695D02*
X74985D01*
G02Y1637495I0J-1600D01*
G01X70685D01*
G02Y1640695I0J1600D01*
G01X72017Y1810723D02*
X62402Y1800512D01*
G01X69681Y1806055D02*
X72017Y1810723D01*
X67497Y1808111D01*
X69681Y1806055D01*
G01X70685Y1813923D02*
X74985D01*
G02Y1810723I0J-1600D01*
G01X70685D01*
G02Y1813923I0J1600D01*
G01X139763Y15072D02*
Y17717D01*
G03X127952I-5906J0D01*
G01Y15072D01*
G02X126202Y10123I-7873J0D01*
G03X141513I7656J-6187D01*
G02X139763Y15072I6123J4949D01*
G01X139808Y15066D02*
X145663Y5923D01*
G01X143768Y11664D02*
X139808Y15066D01*
X141241Y10046D01*
X143768Y11664D01*
G01X172078Y181403D02*
X181693Y191614D01*
G01X174414Y186071D02*
X172078Y181403D01*
X176598Y184015D01*
X174414Y186071D01*
G01X173410Y178203D02*
X169110D01*
G02Y181403I0J1600D01*
G01X173410D01*
G02Y178203I0J-1600D01*
G01X172397Y351431D02*
X182473Y341441D01*
G01X177004Y348976D02*
X172397Y351431D01*
X174891Y346845D01*
X177004Y348976D01*
G01X173410Y351431D02*
X169110D01*
G02Y354631I0J1600D01*
G01X173410D01*
G02Y351431I0J-1600D01*
G01X172078Y586915D02*
X181693Y597126D01*
G01X174414Y591583D02*
X172078Y586915D01*
X176598Y589527D01*
X174414Y591583D01*
G01X173410Y583715D02*
X169110D01*
G02Y586915I0J1600D01*
G01X173410D01*
G02Y583715I0J-1600D01*
G01X172397Y756943D02*
X182473Y746953D01*
G01X177004Y754488D02*
X172397Y756943D01*
X174891Y752357D01*
X177004Y754488D01*
G01X173410Y756943D02*
X169110D01*
G02Y760143I0J1600D01*
G01X173410D01*
G02Y756943I0J-1600D01*
G01X172078Y992427D02*
X181693Y1002638D01*
G01X174414Y997095D02*
X172078Y992427D01*
X176598Y995039D01*
X174414Y997095D01*
G01X173410Y989227D02*
X169110D01*
G02Y992427I0J1600D01*
G01X173410D01*
G02Y989227I0J-1600D01*
G01X172397Y1162455D02*
X182473Y1152465D01*
G01X177004Y1160000D02*
X172397Y1162455D01*
X174891Y1157869D01*
X177004Y1160000D01*
G01X173410Y1162455D02*
X169110D01*
G02Y1165655I0J1600D01*
G01X173410D01*
G02Y1162455I0J-1600D01*
G01X172078Y1397939D02*
X181693Y1408150D01*
G01X174414Y1402607D02*
X172078Y1397939D01*
X176598Y1400551D01*
X174414Y1402607D01*
G01X173410Y1394739D02*
X169110D01*
G02Y1397939I0J1600D01*
G01X173410D01*
G02Y1394739I0J-1600D01*
G01X172397Y1567967D02*
X182473Y1557977D01*
G01X177004Y1565512D02*
X172397Y1567967D01*
X174891Y1563381D01*
X177004Y1565512D01*
G01X173410Y1567967D02*
X169110D01*
G02Y1571167I0J1600D01*
G01X173410D01*
G02Y1567967I0J-1600D01*
G01X172078Y1803451D02*
X181693Y1813662D01*
G01X174414Y1808119D02*
X172078Y1803451D01*
X176598Y1806063D01*
X174414Y1808119D01*
G01X173410Y1800251D02*
X169110D01*
G02Y1803451I0J1600D01*
G01X173410D01*
G02Y1800251I0J-1600D01*
G01X172397Y1973479D02*
X182473Y1963489D01*
G01X177004Y1971024D02*
X172397Y1973479D01*
X174891Y1968893D01*
X177004Y1971024D01*
G01X173410Y1973479D02*
X169110D01*
G02Y1976679I0J1600D01*
G01X173410D01*
G02Y1973479I0J-1600D01*
G01X252500Y-249955D02*
Y-232455D01*
X257740D01*
X259487Y-233330D01*
X260797Y-235372D01*
X261234Y-237705D01*
X260797Y-240038D01*
X259705Y-241788D01*
X257740Y-242664D01*
X252500D01*
G01X279170Y-233914D02*
X277860Y-233038D01*
X276332Y-232455D01*
X274585D01*
X272620Y-233330D01*
X271092Y-234788D01*
X270000Y-236539D01*
X269127Y-239455D01*
X268908Y-242080D01*
X269345Y-244705D01*
X270000Y-246455D01*
X271310Y-248205D01*
X272839Y-249372D01*
X274367Y-249955D01*
X275895D01*
X277424Y-249372D01*
X278734Y-248497D01*
X279826Y-247331D01*
G01X293613Y-240622D02*
X294487Y-239747D01*
X295142Y-238289D01*
X295579Y-236246D01*
X295142Y-234497D01*
X294269Y-233330D01*
X292740Y-232455D01*
X286845D01*
Y-249955D01*
X294050D01*
X295579Y-248789D01*
X296452Y-247038D01*
X296889Y-244997D01*
X296452Y-242955D01*
X295142Y-241205D01*
X293613Y-240622D01*
X286845D01*
G01X302817Y-255788D02*
X315917D01*
G01X321845Y-249955D02*
Y-232455D01*
X331889Y-249955D01*
Y-232455D01*
G01X344367Y-249955D02*
X342620Y-249663D01*
X341092Y-248497D01*
X339782Y-246747D01*
X338908Y-244705D01*
X338472Y-242372D01*
Y-240038D01*
X338908Y-237705D01*
X339782Y-235663D01*
X341092Y-233914D01*
X342620Y-232747D01*
X344367Y-232455D01*
X346113Y-232747D01*
X347642Y-233914D01*
X348952Y-235663D01*
X349826Y-237705D01*
X350262Y-240038D01*
Y-242372D01*
X349826Y-244705D01*
X348952Y-246747D01*
X347642Y-248497D01*
X346113Y-249663D01*
X344367Y-249955D01*
G01X265617Y-294955D02*
Y-277455D01*
X262997Y-280955D01*
G01Y-294955D02*
X268237D01*
G01X278314Y-292331D02*
X279623Y-293789D01*
X281152Y-294663D01*
X283117Y-294955D01*
X285082Y-294372D01*
X286610Y-293205D01*
X287702Y-291164D01*
X287920Y-288830D01*
X287484Y-286497D01*
X286392Y-285038D01*
X284863Y-283872D01*
X283335Y-283580D01*
X281807Y-283872D01*
X279842Y-285038D01*
X280497Y-277455D01*
X286392D01*
G01X296469Y-287664D02*
X297997Y-285622D01*
X299307Y-284455D01*
X301054Y-283872D01*
X302582Y-284455D01*
X303674Y-285622D01*
X304547Y-287372D01*
X304765Y-289413D01*
X304547Y-291164D01*
X303674Y-292914D01*
X302363Y-294372D01*
X300835Y-294955D01*
X299089Y-294372D01*
X297560Y-292622D01*
X296687Y-289997D01*
X296469Y-287080D01*
X296905Y-283289D01*
X297560Y-281246D01*
X298652Y-279205D01*
X300180Y-277747D01*
X301709Y-277455D01*
X303237Y-278038D01*
X304329Y-279497D01*
G01X313969Y-287664D02*
X315497Y-285622D01*
X316807Y-284455D01*
X318554Y-283872D01*
X320082Y-284455D01*
X321174Y-285622D01*
X322047Y-287372D01*
X322265Y-289413D01*
X322047Y-291164D01*
X321174Y-292914D01*
X319863Y-294372D01*
X318335Y-294955D01*
X316589Y-294372D01*
X315060Y-292622D01*
X314187Y-289997D01*
X313969Y-287080D01*
X314405Y-283289D01*
X315060Y-281246D01*
X316152Y-279205D01*
X317680Y-277747D01*
X319209Y-277455D01*
X320737Y-278038D01*
X321829Y-279497D01*
G01X331905Y-292914D02*
X333434Y-294372D01*
X335180Y-294955D01*
X336927Y-294372D01*
X338455Y-292622D01*
X339547Y-289997D01*
X339984Y-287372D01*
Y-284164D01*
X339547Y-281539D01*
X338455Y-279205D01*
X337145Y-278038D01*
X335617Y-277455D01*
X333870Y-278038D01*
X332560Y-279205D01*
X331687Y-280955D01*
X331250Y-283289D01*
X331687Y-285330D01*
X332779Y-287372D01*
X334089Y-288539D01*
X335617Y-288830D01*
X337363Y-288247D01*
X338674Y-286788D01*
X339984Y-284164D01*
G01X281496Y276883D02*
Y279528D01*
G03X269685I-5905J0D01*
G01Y276883D01*
G02X267935Y271934I-7873J0D01*
G03X283246I7656J-6187D01*
G02X281496Y276883I6123J4949D01*
G01X281541Y276877D02*
X287396Y267734D01*
G01X285501Y273475D02*
X281541Y276877D01*
X282974Y271857D01*
X285501Y273475D01*
G01X281496Y682385D02*
Y685030D01*
G03X269685I-5905J0D01*
G01Y682385D01*
G02X267935Y677436I-7873J0D01*
G03X283246I7656J-6187D01*
G02X281496Y682385I6123J4949D01*
G01X281541Y682379D02*
X287396Y673236D01*
G01X285501Y678977D02*
X281541Y682379D01*
X282974Y677359D01*
X285501Y678977D01*
G01X281496Y1085928D02*
Y1088573D01*
G03X269685I-5905J0D01*
G01Y1085928D01*
G02X267935Y1080979I-7873J0D01*
G03X283246I7656J-6187D01*
G02X281496Y1085928I6123J4949D01*
G01X281541Y1085922D02*
X287396Y1076779D01*
G01X285501Y1082520D02*
X281541Y1085922D01*
X282974Y1080902D01*
X285501Y1082520D01*
G01X281496Y1900889D02*
Y1903534D01*
G03X269685I-5905J0D01*
G01Y1900889D01*
G02X267935Y1895940I-7873J0D01*
G03X283246I7656J-6187D01*
G02X281496Y1900889I6123J4949D01*
G01X281541Y1900883D02*
X287396Y1891740D01*
G01X285501Y1897481D02*
X281541Y1900883D01*
X282974Y1895863D01*
X285501Y1897481D01*
G01X395208Y-232455D02*
X400667Y-249955D01*
X406126Y-232455D01*
G01X422534Y-249955D02*
X413800D01*
Y-232455D01*
X422534D01*
G01X419040Y-240913D02*
X413800D01*
G01X431300Y-249955D02*
Y-232455D01*
X436759D01*
X438505Y-233330D01*
X439597Y-234497D01*
X440034Y-236830D01*
X439597Y-239164D01*
X438287Y-240622D01*
X436759Y-241497D01*
X431300D01*
G01X436759D02*
X440034Y-249955D01*
G01X453167Y-250538D02*
X452730Y-250247D01*
Y-249663D01*
X453167Y-249372D01*
X453604Y-249663D01*
Y-250247D01*
X453167Y-250538D01*
G01X426917Y-294955D02*
Y-277455D01*
X424297Y-280955D01*
G01Y-294955D02*
X429537D01*
G01X528750Y-232455D02*
Y-249955D01*
X537484D01*
G01X554547D02*
Y-238289D01*
G01Y-240330D02*
X553674Y-239164D01*
X552363Y-238580D01*
X550835Y-238289D01*
X549307Y-238872D01*
X547997Y-240038D01*
X547123Y-241788D01*
X546687Y-244122D01*
X547123Y-246455D01*
X547997Y-248205D01*
X549307Y-249372D01*
X550835Y-249955D01*
X552363Y-249663D01*
X553674Y-248789D01*
X554547Y-247622D01*
G01X563532Y-255205D02*
X564842Y-255788D01*
X566589Y-255205D01*
X567680Y-254039D01*
X568554Y-252580D01*
X569863Y-247914D01*
X572702Y-238289D01*
G01X565715D02*
X569863Y-247914D01*
G01X582342Y-242080D02*
X589329D01*
X588674Y-240038D01*
X587582Y-238872D01*
X586054Y-238289D01*
X584525Y-238580D01*
X583215Y-239455D01*
X582342Y-241497D01*
X581905Y-243247D01*
Y-244997D01*
X582342Y-246747D01*
X583434Y-248497D01*
X584744Y-249663D01*
X586272Y-249955D01*
X587800Y-249372D01*
X589329Y-247622D01*
G01X600060Y-249955D02*
Y-238289D01*
G01Y-240622D02*
X601152Y-239455D01*
X602244Y-238580D01*
X603772Y-238289D01*
X604863Y-238580D01*
X606174Y-239455D01*
G01X528314Y-294955D02*
Y-277455D01*
X532680D01*
X534427Y-278330D01*
X535737Y-279497D01*
X536829Y-281246D01*
X537702Y-283289D01*
X537920Y-286205D01*
X537702Y-289122D01*
X536829Y-291164D01*
X535737Y-292914D01*
X534427Y-294080D01*
X532680Y-294955D01*
X528314D01*
G01X546250D02*
Y-277455D01*
X551709D01*
X553455Y-278330D01*
X554547Y-279497D01*
X554984Y-281830D01*
X554547Y-284164D01*
X553237Y-285622D01*
X551709Y-286497D01*
X546250D01*
G01X551709D02*
X554984Y-294955D01*
G01X565497Y-277455D02*
X570737D01*
G01X568117D02*
Y-294955D01*
G01X565497D02*
X570737D01*
G01X581250Y-277455D02*
Y-294955D01*
X589984D01*
G01X598750Y-277455D02*
Y-294955D01*
X607484D01*
G01X670864Y-249955D02*
Y-232455D01*
X675230D01*
X676977Y-233330D01*
X678287Y-234497D01*
X679379Y-236246D01*
X680252Y-238289D01*
X680470Y-241205D01*
X680252Y-244122D01*
X679379Y-246164D01*
X678287Y-247914D01*
X676977Y-249080D01*
X675230Y-249955D01*
X670864D01*
G01X689892Y-242080D02*
X696879D01*
X696224Y-240038D01*
X695132Y-238872D01*
X693604Y-238289D01*
X692075Y-238580D01*
X690765Y-239455D01*
X689892Y-241497D01*
X689455Y-243247D01*
Y-244997D01*
X689892Y-246747D01*
X690984Y-248497D01*
X692294Y-249663D01*
X693822Y-249955D01*
X695350Y-249372D01*
X696879Y-247622D01*
G01X707392Y-247914D02*
X708484Y-249080D01*
X710012Y-249955D01*
X711322D01*
X712632Y-249372D01*
X713505Y-248497D01*
X713942Y-247331D01*
X713724Y-245580D01*
X712850Y-244705D01*
X708920Y-242955D01*
X708047Y-240913D01*
X708484Y-239455D01*
X709357Y-238580D01*
X710667Y-238289D01*
X711977Y-238580D01*
X713287Y-239455D01*
G01X728167Y-238289D02*
Y-249955D01*
G01Y-233622D02*
X727730Y-233330D01*
Y-232747D01*
X728167Y-232455D01*
X728604Y-232747D01*
Y-233330D01*
X728167Y-233622D01*
G01X742610Y-254330D02*
X744139Y-255497D01*
X745885Y-255788D01*
X747413Y-255497D01*
X748724Y-254039D01*
X749597Y-251997D01*
Y-238289D01*
G01Y-240622D02*
X748724Y-239455D01*
X747413Y-238580D01*
X745885Y-238289D01*
X744139Y-238872D01*
X743047Y-240038D01*
X742173Y-242080D01*
X741737Y-244122D01*
X741955Y-245872D01*
X742829Y-247914D01*
X744139Y-249372D01*
X745885Y-249955D01*
X747195Y-249663D01*
X748724Y-248497D01*
X749597Y-247331D01*
G01X759455Y-249955D02*
Y-238289D01*
G01Y-241205D02*
X760329Y-239747D01*
X761639Y-238580D01*
X763385Y-238289D01*
X764913Y-238580D01*
X766224Y-239747D01*
X766879Y-241788D01*
Y-249955D01*
G01X777392Y-242080D02*
X784379D01*
X783724Y-240038D01*
X782632Y-238872D01*
X781104Y-238289D01*
X779575Y-238580D01*
X778265Y-239455D01*
X777392Y-241497D01*
X776955Y-243247D01*
Y-244997D01*
X777392Y-246747D01*
X778484Y-248497D01*
X779794Y-249663D01*
X781322Y-249955D01*
X782850Y-249372D01*
X784379Y-247622D01*
G01X795110Y-249955D02*
Y-238289D01*
G01Y-240622D02*
X796202Y-239455D01*
X797294Y-238580D01*
X798822Y-238289D01*
X799913Y-238580D01*
X801224Y-239455D01*
G01X660367Y-277455D02*
X663423Y-294955D01*
X666917Y-277455D01*
X670410Y-294955D01*
X673467Y-277455D01*
G01X680050Y-294955D02*
Y-277455D01*
X685290D01*
X687037Y-278330D01*
X688347Y-280372D01*
X688784Y-282705D01*
X688347Y-285038D01*
X687255Y-286788D01*
X685290Y-287664D01*
X680050D01*
G01X697332Y-294955D02*
Y-277455D01*
G01X706502D02*
Y-294955D01*
G01Y-286205D02*
X697332D01*
G01X716579Y-289122D02*
X722255D01*
G01X732769Y-294955D02*
Y-277455D01*
X741065D01*
G01X738009Y-285913D02*
X732769D01*
G01X750050Y-277455D02*
Y-294955D01*
X758784D01*
G01X771917D02*
X770170Y-294663D01*
X768642Y-293497D01*
X767332Y-291747D01*
X766458Y-289705D01*
X766022Y-287372D01*
Y-285038D01*
X766458Y-282705D01*
X767332Y-280663D01*
X768642Y-278914D01*
X770170Y-277747D01*
X771917Y-277455D01*
X773663Y-277747D01*
X775192Y-278914D01*
X776502Y-280663D01*
X777376Y-282705D01*
X777812Y-285038D01*
Y-287372D01*
X777376Y-289705D01*
X776502Y-291747D01*
X775192Y-293497D01*
X773663Y-294663D01*
X771917Y-294955D01*
G01X785050D02*
Y-277455D01*
X790509D01*
X792255Y-278330D01*
X793347Y-279497D01*
X793784Y-281830D01*
X793347Y-284164D01*
X792037Y-285622D01*
X790509Y-286497D01*
X785050D01*
G01X790509D02*
X793784Y-294955D01*
G01X801458D02*
X806917Y-277455D01*
X812376Y-294955D01*
G01X810410Y-288830D02*
X803423D01*
G01X841867Y-294955D02*
Y-277455D01*
X839247Y-280955D01*
G01Y-294955D02*
X844487D01*
G01X859367D02*
Y-277455D01*
X856747Y-280955D01*
G01Y-294955D02*
X861987D01*
G01X872937Y-295538D02*
X880797Y-277455D01*
G01X894367Y-294955D02*
Y-277455D01*
X891747Y-280955D01*
G01Y-294955D02*
X896987D01*
G01X907719Y-287664D02*
X909247Y-285622D01*
X910557Y-284455D01*
X912304Y-283872D01*
X913832Y-284455D01*
X914924Y-285622D01*
X915797Y-287372D01*
X916015Y-289413D01*
X915797Y-291164D01*
X914924Y-292914D01*
X913613Y-294372D01*
X912085Y-294955D01*
X910339Y-294372D01*
X908810Y-292622D01*
X907937Y-289997D01*
X907719Y-287080D01*
X908155Y-283289D01*
X908810Y-281246D01*
X909902Y-279205D01*
X911430Y-277747D01*
X912959Y-277455D01*
X914487Y-278038D01*
X915579Y-279497D01*
G01X925437Y-295538D02*
X933297Y-277455D01*
G01X942719Y-280372D02*
X944029Y-278622D01*
X945557Y-277747D01*
X947304Y-277455D01*
X949487Y-278038D01*
X951015Y-279497D01*
X951452Y-281246D01*
X951234Y-282997D01*
X950360Y-284455D01*
X945994Y-287372D01*
X944029Y-289413D01*
X942719Y-292331D01*
X942282Y-294955D01*
X951452D01*
G01X964367Y-277455D02*
X962620Y-278038D01*
X961310Y-279497D01*
X960437Y-281246D01*
X959782Y-283580D01*
X959564Y-286205D01*
X959782Y-288830D01*
X960437Y-291164D01*
X961310Y-292914D01*
X962620Y-294372D01*
X964367Y-294955D01*
X966113Y-294372D01*
X967424Y-292914D01*
X968297Y-291164D01*
X968952Y-288830D01*
X969170Y-286205D01*
X968952Y-283580D01*
X968297Y-281246D01*
X967424Y-279497D01*
X966113Y-278038D01*
X964367Y-277455D01*
G01X981867Y-294955D02*
Y-277455D01*
X979247Y-280955D01*
G01Y-294955D02*
X984487D01*
G01X995219Y-287664D02*
X996747Y-285622D01*
X998057Y-284455D01*
X999804Y-283872D01*
X1001332Y-284455D01*
X1002424Y-285622D01*
X1003297Y-287372D01*
X1003515Y-289413D01*
X1003297Y-291164D01*
X1002424Y-292914D01*
X1001113Y-294372D01*
X999585Y-294955D01*
X997839Y-294372D01*
X996310Y-292622D01*
X995437Y-289997D01*
X995219Y-287080D01*
X995655Y-283289D01*
X996310Y-281246D01*
X997402Y-279205D01*
X998930Y-277747D01*
X1000459Y-277455D01*
X1001987Y-278038D01*
X1003079Y-279497D01*
G01X889564Y-249955D02*
Y-232455D01*
X893930D01*
X895677Y-233330D01*
X896987Y-234497D01*
X898079Y-236246D01*
X898952Y-238289D01*
X899170Y-241205D01*
X898952Y-244122D01*
X898079Y-246164D01*
X896987Y-247914D01*
X895677Y-249080D01*
X893930Y-249955D01*
X889564D01*
G01X915797D02*
Y-238289D01*
G01Y-240330D02*
X914924Y-239164D01*
X913613Y-238580D01*
X912085Y-238289D01*
X910557Y-238872D01*
X909247Y-240038D01*
X908373Y-241788D01*
X907937Y-244122D01*
X908373Y-246455D01*
X909247Y-248205D01*
X910557Y-249372D01*
X912085Y-249955D01*
X913613Y-249663D01*
X914924Y-248789D01*
X915797Y-247622D01*
G01X929367Y-232455D02*
Y-249955D01*
G01X926310Y-238289D02*
X932424D01*
G01X943592Y-242080D02*
X950579D01*
X949924Y-240038D01*
X948832Y-238872D01*
X947304Y-238289D01*
X945775Y-238580D01*
X944465Y-239455D01*
X943592Y-241497D01*
X943155Y-243247D01*
Y-244997D01*
X943592Y-246747D01*
X944684Y-248497D01*
X945994Y-249663D01*
X947522Y-249955D01*
X949050Y-249372D01*
X950579Y-247622D01*
G01X900424Y181403D02*
X910039Y191614D01*
G01X902760Y186071D02*
X900424Y181403D01*
X904944Y184015D01*
X902760Y186071D01*
G01X901756Y178203D02*
X897456D01*
G02Y181403I0J1600D01*
G01X901756D01*
G02Y178203I0J-1600D01*
G01X900743Y351431D02*
X910819Y341441D01*
G01X905350Y348976D02*
X900743Y351431D01*
X903237Y346845D01*
X905350Y348976D01*
G01X901756Y351431D02*
X897456D01*
G02Y354631I0J1600D01*
G01X901756D01*
G02Y351431I0J-1600D01*
G01X900424Y586915D02*
X910039Y597126D01*
G01X902760Y591583D02*
X900424Y586915D01*
X904944Y589527D01*
X902760Y591583D01*
G01X901756Y583715D02*
X897456D01*
G02Y586915I0J1600D01*
G01X901756D01*
G02Y583715I0J-1600D01*
G01X900743Y756943D02*
X910819Y746953D01*
G01X905350Y754488D02*
X900743Y756943D01*
X903237Y752357D01*
X905350Y754488D01*
G01X901756Y756943D02*
X897456D01*
G02Y760143I0J1600D01*
G01X901756D01*
G02Y756943I0J-1600D01*
G01X900424Y992427D02*
X910039Y1002638D01*
G01X902760Y997095D02*
X900424Y992427D01*
X904944Y995039D01*
X902760Y997095D01*
G01X901756Y989227D02*
X897456D01*
G02Y992427I0J1600D01*
G01X901756D01*
G02Y989227I0J-1600D01*
G01X900743Y1162455D02*
X910819Y1152465D01*
G01X905350Y1160000D02*
X900743Y1162455D01*
X903237Y1157869D01*
X905350Y1160000D01*
G01X901756Y1162455D02*
X897456D01*
G02Y1165655I0J1600D01*
G01X901756D01*
G02Y1162455I0J-1600D01*
G01X900424Y1397939D02*
X910039Y1408150D01*
G01X902760Y1402607D02*
X900424Y1397939D01*
X904944Y1400551D01*
X902760Y1402607D01*
G01X901756Y1394739D02*
X897456D01*
G02Y1397939I0J1600D01*
G01X901756D01*
G02Y1394739I0J-1600D01*
G01X900743Y1567967D02*
X910819Y1557977D01*
G01X905350Y1565512D02*
X900743Y1567967D01*
X903237Y1563381D01*
X905350Y1565512D01*
G01X901756Y1567967D02*
X897456D01*
G02Y1571167I0J1600D01*
G01X901756D01*
G02Y1567967I0J-1600D01*
G01X900424Y1803451D02*
X910039Y1813662D01*
G01X902760Y1808119D02*
X900424Y1803451D01*
X904944Y1806063D01*
X902760Y1808119D01*
G01X901756Y1800251D02*
X897456D01*
G02Y1803451I0J1600D01*
G01X901756D01*
G02Y1800251I0J-1600D01*
G01X900743Y1973479D02*
X910819Y1963489D01*
G01X905350Y1971024D02*
X900743Y1973479D01*
X903237Y1968893D01*
X905350Y1971024D01*
G01X901756Y1973479D02*
X897456D01*
G02Y1976679I0J1600D01*
G01X901756D01*
G02Y1973479I0J-1600D01*
G01X1003936Y160731D02*
Y163376D01*
G03X992125I-5905J0D01*
G01Y160731D01*
G02X990375Y155782I-7873J0D01*
G03X1005686I7656J-6187D01*
G02X1003936Y160731I6123J4949D01*
G01X1003981Y160725D02*
X1009836Y151582D01*
G01X1007941Y157323D02*
X1003981Y160725D01*
X1005414Y155705D01*
X1007941Y157323D01*
G01X1003936Y684353D02*
Y686998D01*
G03X992125I-5905J0D01*
G01Y684353D01*
G02X990375Y679404I-7873J0D01*
G03X1005686I7656J-6187D01*
G02X1003936Y684353I6123J4949D01*
G01X1003981Y684347D02*
X1009836Y675204D01*
G01X1007941Y680945D02*
X1003981Y684347D01*
X1005414Y679327D01*
X1007941Y680945D01*
G01X1003936Y1080022D02*
Y1082667D01*
G03X992125I-5905J0D01*
G01Y1080022D01*
G02X990375Y1075073I-7873J0D01*
G03X1005686I7656J-6187D01*
G02X1003936Y1080022I6123J4949D01*
G01X1003981Y1080016D02*
X1009836Y1070873D01*
G01X1007941Y1076614D02*
X1003981Y1080016D01*
X1005414Y1074996D01*
X1007941Y1076614D01*
G01X1003936Y1900889D02*
Y1903534D01*
G03X992125I-5905J0D01*
G01Y1900889D01*
G02X990375Y1895940I-7873J0D01*
G03X1005686I7656J-6187D01*
G02X1003936Y1900889I6123J4949D01*
G01X1003981Y1900883D02*
X1009836Y1891740D01*
G01X1007941Y1897481D02*
X1003981Y1900883D01*
X1005414Y1895863D01*
X1007941Y1897481D01*
G01X1228131Y92329D02*
Y104829D01*
X1235261Y92329D01*
Y104829D01*
G01X1244096Y92329D02*
X1243166Y92537D01*
X1242236Y93370D01*
X1241616Y94829D01*
X1241306Y96496D01*
X1241616Y98162D01*
X1242236Y99621D01*
X1243166Y100454D01*
X1244096Y100662D01*
X1245026Y100454D01*
X1245956Y99621D01*
X1246576Y98162D01*
X1246731Y96496D01*
X1246576Y94829D01*
X1245956Y93370D01*
X1245026Y92537D01*
X1244096Y92329D01*
G01X1256496Y104829D02*
Y92329D01*
G01X1254326Y100662D02*
X1258666D01*
G01X1266571Y97954D02*
X1271531D01*
X1271066Y99412D01*
X1270291Y100246D01*
X1269206Y100662D01*
X1268121Y100454D01*
X1267191Y99829D01*
X1266571Y98371D01*
X1266261Y97120D01*
Y95871D01*
X1266571Y94621D01*
X1267346Y93370D01*
X1268276Y92537D01*
X1269361Y92329D01*
X1270446Y92746D01*
X1271531Y93995D01*
G01X1281296Y91912D02*
X1280986Y92121D01*
Y92537D01*
X1281296Y92746D01*
X1281606Y92537D01*
Y92121D01*
X1281296Y91912D01*
G01Y97537D02*
X1280986Y97746D01*
Y98162D01*
X1281296Y98371D01*
X1281606Y98162D01*
Y97746D01*
X1281296Y97537D01*
G01X1290596Y92329D02*
Y104829D01*
X1294471D01*
X1295711Y104204D01*
X1296486Y103371D01*
X1296796Y101704D01*
X1296486Y100037D01*
X1295556Y98996D01*
X1294471Y98371D01*
X1290596D01*
G01X1294471D02*
X1296796Y92329D01*
G01X1303771Y97954D02*
X1308731D01*
X1308266Y99412D01*
X1307491Y100246D01*
X1306406Y100662D01*
X1305321Y100454D01*
X1304391Y99829D01*
X1303771Y98371D01*
X1303461Y97120D01*
Y95871D01*
X1303771Y94621D01*
X1304546Y93370D01*
X1305476Y92537D01*
X1306561Y92329D01*
X1307646Y92746D01*
X1308731Y93995D01*
G01X1317566Y92329D02*
Y102954D01*
X1317876Y103995D01*
X1318496Y104621D01*
X1319426Y104829D01*
X1320356Y104412D01*
X1320821Y103371D01*
G01X1318961Y99829D02*
X1315861D01*
G01X1328571Y97954D02*
X1333531D01*
X1333066Y99412D01*
X1332291Y100246D01*
X1331206Y100662D01*
X1330121Y100454D01*
X1329191Y99829D01*
X1328571Y98371D01*
X1328261Y97120D01*
Y95871D01*
X1328571Y94621D01*
X1329346Y93370D01*
X1330276Y92537D01*
X1331361Y92329D01*
X1332446Y92746D01*
X1333531Y93995D01*
G01X1341126Y92329D02*
Y100662D01*
G01Y98996D02*
X1341901Y99829D01*
X1342676Y100454D01*
X1343761Y100662D01*
X1344536Y100454D01*
X1345466Y99829D01*
G01X1368096Y104829D02*
Y92329D01*
G01X1365926Y100662D02*
X1370266D01*
G01X1380496Y92329D02*
X1379566Y92537D01*
X1378636Y93370D01*
X1378016Y94829D01*
X1377706Y96496D01*
X1378016Y98162D01*
X1378636Y99621D01*
X1379566Y100454D01*
X1380496Y100662D01*
X1381426Y100454D01*
X1382356Y99621D01*
X1382976Y98162D01*
X1383131Y96496D01*
X1382976Y94829D01*
X1382356Y93370D01*
X1381426Y92537D01*
X1380496Y92329D01*
G01X1401886D02*
Y104829D01*
X1404986D01*
X1406226Y104204D01*
X1407156Y103371D01*
X1407931Y102121D01*
X1408551Y100662D01*
X1408706Y98579D01*
X1408551Y96496D01*
X1407931Y95037D01*
X1407156Y93787D01*
X1406226Y92954D01*
X1404986Y92329D01*
X1401886D01*
G01X1414596D02*
Y104829D01*
X1418471D01*
X1419711Y104204D01*
X1420486Y103371D01*
X1420796Y101704D01*
X1420486Y100037D01*
X1419556Y98996D01*
X1418471Y98371D01*
X1414596D01*
G01X1418471D02*
X1420796Y92329D01*
G01X1428236Y104829D02*
X1431956D01*
G01X1430096D02*
Y92329D01*
G01X1428236D02*
X1431956D01*
G01X1439396Y104829D02*
Y92329D01*
X1445596D01*
G01X1451796Y104829D02*
Y92329D01*
X1457996D01*
G01X1479696D02*
Y104829D01*
G01X1494886Y92329D02*
Y100662D01*
G01Y99204D02*
X1494266Y100037D01*
X1493336Y100454D01*
X1492251Y100662D01*
X1491166Y100246D01*
X1490236Y99412D01*
X1489616Y98162D01*
X1489306Y96496D01*
X1489616Y94829D01*
X1490236Y93579D01*
X1491166Y92746D01*
X1492251Y92329D01*
X1493336Y92537D01*
X1494266Y93162D01*
X1494886Y93995D01*
G01X1501241Y88579D02*
X1502171Y88162D01*
X1503411Y88579D01*
X1504186Y89412D01*
X1504806Y90454D01*
X1505736Y93787D01*
X1507751Y100662D01*
G01X1502791D02*
X1505736Y93787D01*
G01X1514571Y97954D02*
X1519531D01*
X1519066Y99412D01*
X1518291Y100246D01*
X1517206Y100662D01*
X1516121Y100454D01*
X1515191Y99829D01*
X1514571Y98371D01*
X1514261Y97120D01*
Y95871D01*
X1514571Y94621D01*
X1515346Y93370D01*
X1516276Y92537D01*
X1517361Y92329D01*
X1518446Y92746D01*
X1519531Y93995D01*
G01X1527126Y92329D02*
Y100662D01*
G01Y98996D02*
X1527901Y99829D01*
X1528676Y100454D01*
X1529761Y100662D01*
X1530536Y100454D01*
X1531466Y99829D01*
G01X1553166Y92329D02*
Y102954D01*
X1553476Y103995D01*
X1554096Y104621D01*
X1555026Y104829D01*
X1555956Y104412D01*
X1556421Y103371D01*
G01X1554561Y99829D02*
X1551461D01*
G01X1566496Y92329D02*
X1565566Y92537D01*
X1564636Y93370D01*
X1564016Y94829D01*
X1563706Y96496D01*
X1564016Y98162D01*
X1564636Y99621D01*
X1565566Y100454D01*
X1566496Y100662D01*
X1567426Y100454D01*
X1568356Y99621D01*
X1568976Y98162D01*
X1569131Y96496D01*
X1568976Y94829D01*
X1568356Y93370D01*
X1567426Y92537D01*
X1566496Y92329D01*
G01X1576726D02*
Y100662D01*
G01Y98996D02*
X1577501Y99829D01*
X1578276Y100454D01*
X1579361Y100662D01*
X1580136Y100454D01*
X1581066Y99829D01*
G01X1606796Y92329D02*
X1600596D01*
Y104829D01*
X1606796D01*
G01X1604316Y98787D02*
X1600596D01*
G01X1612996Y104829D02*
Y92329D01*
X1619196D01*
G01X1625396Y104829D02*
Y92329D01*
X1631596D01*
G01X1639036Y104829D02*
X1642756D01*
G01X1640896D02*
Y92329D01*
G01X1639036D02*
X1642756D01*
G01X1650196D02*
Y104829D01*
X1653916D01*
X1655156Y104204D01*
X1656086Y102746D01*
X1656396Y101079D01*
X1656086Y99412D01*
X1655311Y98162D01*
X1653916Y97537D01*
X1650196D01*
G01X1662441Y93995D02*
X1663681Y92954D01*
X1665076Y92329D01*
X1666316D01*
X1667556Y92954D01*
X1668486Y93995D01*
X1668951Y95454D01*
X1668641Y96912D01*
X1667866Y98162D01*
X1666471Y98996D01*
X1664611Y99412D01*
X1663526Y100246D01*
X1663061Y101704D01*
X1663371Y103162D01*
X1664146Y104204D01*
X1665231Y104829D01*
X1666316D01*
X1667401Y104412D01*
X1668331Y103371D01*
G01X1681196Y92329D02*
X1674996D01*
Y104829D01*
X1681196D01*
G01X1678716Y98787D02*
X1674996D01*
G01X1705686Y104829D02*
Y92329D01*
G01Y94204D02*
X1705066Y93162D01*
X1704136Y92537D01*
X1703051Y92329D01*
X1701811Y92746D01*
X1700881Y93787D01*
X1700261Y95037D01*
X1700106Y96496D01*
X1700261Y97954D01*
X1700881Y99204D01*
X1701811Y100246D01*
X1703051Y100662D01*
X1704136Y100454D01*
X1704911Y100037D01*
X1705686Y99204D01*
G01X1713126Y92329D02*
Y100662D01*
G01Y98996D02*
X1713901Y99829D01*
X1714676Y100454D01*
X1715761Y100662D01*
X1716536Y100454D01*
X1717466Y99829D01*
G01X1727696Y100662D02*
Y92329D01*
G01Y103995D02*
X1727386Y104204D01*
Y104621D01*
X1727696Y104829D01*
X1728006Y104621D01*
Y104204D01*
X1727696Y103995D01*
G01X1740096Y92329D02*
Y104829D01*
G01X1752496Y92329D02*
Y104829D01*
G01X1780086D02*
Y92329D01*
G01Y94204D02*
X1779466Y93162D01*
X1778536Y92537D01*
X1777451Y92329D01*
X1776211Y92746D01*
X1775281Y93787D01*
X1774661Y95037D01*
X1774506Y96496D01*
X1774661Y97954D01*
X1775281Y99204D01*
X1776211Y100246D01*
X1777451Y100662D01*
X1778536Y100454D01*
X1779311Y100037D01*
X1780086Y99204D01*
G01X1789696Y100662D02*
Y92329D01*
G01Y103995D02*
X1789386Y104204D01*
Y104621D01*
X1789696Y104829D01*
X1790006Y104621D01*
Y104204D01*
X1789696Y103995D01*
G01X1799926Y92329D02*
Y100662D01*
G01Y98996D02*
X1800701Y99829D01*
X1801476Y100454D01*
X1802561Y100662D01*
X1803336Y100454D01*
X1804266Y99829D01*
G01X1812171Y97954D02*
X1817131D01*
X1816666Y99412D01*
X1815891Y100246D01*
X1814806Y100662D01*
X1813721Y100454D01*
X1812791Y99829D01*
X1812171Y98371D01*
X1811861Y97120D01*
Y95871D01*
X1812171Y94621D01*
X1812946Y93370D01*
X1813876Y92537D01*
X1814961Y92329D01*
X1816046Y92746D01*
X1817131Y93995D01*
G01X1829376Y99621D02*
X1828291Y100454D01*
X1827361Y100662D01*
X1826121Y100246D01*
X1825191Y99412D01*
X1824571Y97954D01*
X1824416Y96496D01*
X1824571Y95037D01*
X1825191Y93787D01*
X1826121Y92746D01*
X1827361Y92329D01*
X1828446Y92746D01*
X1829376Y93579D01*
G01X1839296Y104829D02*
Y92329D01*
G01X1837126Y100662D02*
X1841466D01*
G01X1851696D02*
Y92329D01*
G01Y103995D02*
X1851386Y104204D01*
Y104621D01*
X1851696Y104829D01*
X1852006Y104621D01*
Y104204D01*
X1851696Y103995D01*
G01X1864096Y92329D02*
X1863166Y92537D01*
X1862236Y93370D01*
X1861616Y94829D01*
X1861306Y96496D01*
X1861616Y98162D01*
X1862236Y99621D01*
X1863166Y100454D01*
X1864096Y100662D01*
X1865026Y100454D01*
X1865956Y99621D01*
X1866576Y98162D01*
X1866731Y96496D01*
X1866576Y94829D01*
X1865956Y93370D01*
X1865026Y92537D01*
X1864096Y92329D01*
G01X1873861D02*
Y100662D01*
G01Y98579D02*
X1874481Y99621D01*
X1875411Y100454D01*
X1876651Y100662D01*
X1877736Y100454D01*
X1878666Y99621D01*
X1879131Y98162D01*
Y92329D01*
G01X1227046Y122329D02*
Y512629D01*
X1710646D01*
Y122329D01*
X1227046D01*
G01Y178529D02*
X1710646D01*
G01X1227046Y150429D02*
X1710646D01*
G01X1227046Y262829D02*
X1710646D01*
G01X1227046Y234729D02*
X1710646D01*
G01X1227046Y206629D02*
X1710646D01*
G01X1227046Y319029D02*
X1710646D01*
G01X1227046Y290929D02*
X1710646D01*
G01X1227046Y403329D02*
X1710646D01*
G01X1227046Y375229D02*
X1710646D01*
G01X1227046Y347129D02*
X1710646D01*
G01X1238051Y440779D02*
Y453279D01*
X1243941D01*
G01X1241771Y447237D02*
X1238051D01*
G01X1251536Y453279D02*
X1255256D01*
G01X1253396D02*
Y440779D01*
G01X1251536D02*
X1255256D01*
G01X1266726Y447029D02*
X1269826D01*
Y443279D01*
X1268896Y442029D01*
X1267811Y441196D01*
X1266261Y440779D01*
X1264711Y441196D01*
X1263626Y442029D01*
X1262696Y443279D01*
X1262076Y444737D01*
X1261766Y446404D01*
Y447862D01*
X1262076Y449112D01*
X1262696Y450571D01*
X1263626Y451821D01*
X1264556Y452654D01*
X1265796Y453279D01*
X1266881D01*
X1268121Y452862D01*
X1269051Y452029D01*
G01X1274786Y453279D02*
Y444321D01*
X1275406Y442445D01*
X1276646Y441196D01*
X1278196Y440779D01*
X1279746Y441196D01*
X1280986Y442445D01*
X1281606Y444321D01*
Y453279D01*
G01X1287496Y440779D02*
Y453279D01*
X1291371D01*
X1292611Y452654D01*
X1293386Y451821D01*
X1293696Y450154D01*
X1293386Y448487D01*
X1292456Y447446D01*
X1291371Y446821D01*
X1287496D01*
G01X1291371D02*
X1293696Y440779D01*
G01X1306096D02*
X1299896D01*
Y453279D01*
X1306096D01*
G01X1303616Y447237D02*
X1299896D01*
G01X1227046Y459529D02*
X1710646D01*
G01X1227046Y431429D02*
X1710646D01*
G01X1227046Y487629D02*
X1710646D01*
G01X1316946Y459529D02*
Y122329D01*
G01X1340971Y468879D02*
X1344846Y481379D01*
X1348721Y468879D01*
G01X1347326Y473254D02*
X1342366D01*
G01X1354146Y481379D02*
Y468879D01*
X1360346D01*
G01X1366546Y481379D02*
Y468879D01*
X1372746D01*
G01X1391036Y481379D02*
Y472421D01*
X1391656Y470545D01*
X1392896Y469296D01*
X1394446Y468879D01*
X1395996Y469296D01*
X1397236Y470545D01*
X1397856Y472421D01*
Y481379D01*
G01X1403281Y468879D02*
Y481379D01*
X1410411Y468879D01*
Y481379D01*
G01X1417386D02*
X1421106D01*
G01X1419246D02*
Y468879D01*
G01X1417386D02*
X1421106D01*
G01X1431646Y481379D02*
Y468879D01*
G01X1428081Y481379D02*
X1435211D01*
G01X1440791Y470545D02*
X1442031Y469504D01*
X1443426Y468879D01*
X1444666D01*
X1445906Y469504D01*
X1446836Y470545D01*
X1447301Y472004D01*
X1446991Y473462D01*
X1446216Y474712D01*
X1444821Y475546D01*
X1442961Y475962D01*
X1441876Y476796D01*
X1441411Y478254D01*
X1441721Y479712D01*
X1442496Y480754D01*
X1443581Y481379D01*
X1444666D01*
X1445751Y480962D01*
X1446681Y479921D01*
G01X1464971Y468879D02*
X1468846Y481379D01*
X1472721Y468879D01*
G01X1471326Y473254D02*
X1466366D01*
G01X1478146Y468879D02*
Y481379D01*
X1482021D01*
X1483261Y480754D01*
X1484036Y479921D01*
X1484346Y478254D01*
X1484036Y476587D01*
X1483106Y475546D01*
X1482021Y474921D01*
X1478146D01*
G01X1482021D02*
X1484346Y468879D01*
G01X1496746D02*
X1490546D01*
Y481379D01*
X1496746D01*
G01X1494266Y475337D02*
X1490546D01*
G01X1516586Y481379D02*
X1520306D01*
G01X1518446D02*
Y468879D01*
G01X1516586D02*
X1520306D01*
G01X1527281D02*
Y481379D01*
X1534411Y468879D01*
Y481379D01*
G01X1551616Y468879D02*
Y481379D01*
X1555646Y470962D01*
X1559676Y481379D01*
Y468879D01*
G01X1566186Y481379D02*
X1569906D01*
G01X1568046D02*
Y468879D01*
G01X1566186D02*
X1569906D01*
G01X1577346Y481379D02*
Y468879D01*
X1583546D01*
G01X1589591Y470545D02*
X1590831Y469504D01*
X1592226Y468879D01*
X1593466D01*
X1594706Y469504D01*
X1595636Y470545D01*
X1596101Y472004D01*
X1595791Y473462D01*
X1595016Y474712D01*
X1593621Y475546D01*
X1591761Y475962D01*
X1590676Y476796D01*
X1590211Y478254D01*
X1590521Y479712D01*
X1591296Y480754D01*
X1592381Y481379D01*
X1593466D01*
X1594551Y480962D01*
X1595481Y479921D01*
G01X1310436Y493879D02*
Y506379D01*
X1313536D01*
X1314776Y505754D01*
X1315706Y504921D01*
X1316481Y503671D01*
X1317101Y502212D01*
X1317256Y500129D01*
X1317101Y498046D01*
X1316481Y496587D01*
X1315706Y495337D01*
X1314776Y494504D01*
X1313536Y493879D01*
X1310436D01*
G01X1323146D02*
Y506379D01*
X1327021D01*
X1328261Y505754D01*
X1329036Y504921D01*
X1329346Y503254D01*
X1329036Y501587D01*
X1328106Y500546D01*
X1327021Y499921D01*
X1323146D01*
G01X1327021D02*
X1329346Y493879D01*
G01X1336786Y506379D02*
X1340506D01*
G01X1338646D02*
Y493879D01*
G01X1336786D02*
X1340506D01*
G01X1347946Y506379D02*
Y493879D01*
X1354146D01*
G01X1360346Y506379D02*
Y493879D01*
X1366546D01*
G01X1391656Y505337D02*
X1390726Y505962D01*
X1389641Y506379D01*
X1388401D01*
X1387006Y505754D01*
X1385921Y504712D01*
X1385146Y503462D01*
X1384526Y501379D01*
X1384371Y499504D01*
X1384681Y497629D01*
X1385146Y496379D01*
X1386076Y495129D01*
X1387161Y494296D01*
X1388246Y493879D01*
X1389331D01*
X1390416Y494296D01*
X1391346Y494920D01*
X1392121Y495754D01*
G01X1397391Y493879D02*
Y506379D01*
G01X1403901D02*
Y493879D01*
G01Y500129D02*
X1397391D01*
G01X1409171Y493879D02*
X1413046Y506379D01*
X1416921Y493879D01*
G01X1415526Y498254D02*
X1410566D01*
G01X1422346Y493879D02*
Y506379D01*
X1426221D01*
X1427461Y505754D01*
X1428236Y504921D01*
X1428546Y503254D01*
X1428236Y501587D01*
X1427306Y500546D01*
X1426221Y499921D01*
X1422346D01*
G01X1426221D02*
X1428546Y493879D01*
G01X1437846Y506379D02*
Y493879D01*
G01X1434281Y506379D02*
X1441411D01*
G01X1450246Y493462D02*
X1449936Y493671D01*
Y494087D01*
X1450246Y494296D01*
X1450556Y494087D01*
Y493671D01*
X1450246Y493462D01*
G01Y499087D02*
X1449936Y499296D01*
Y499712D01*
X1450246Y499921D01*
X1450556Y499712D01*
Y499296D01*
X1450246Y499087D01*
G01X1475046Y506379D02*
Y493879D01*
G01X1471481Y506379D02*
X1478611D01*
G01X1487446Y493879D02*
X1486206Y494087D01*
X1485121Y494920D01*
X1484191Y496171D01*
X1483571Y497629D01*
X1483261Y499296D01*
Y500962D01*
X1483571Y502629D01*
X1484191Y504087D01*
X1485121Y505337D01*
X1486206Y506171D01*
X1487446Y506379D01*
X1488686Y506171D01*
X1489771Y505337D01*
X1490701Y504087D01*
X1491321Y502629D01*
X1491631Y500962D01*
Y499296D01*
X1491321Y497629D01*
X1490701Y496171D01*
X1489771Y494920D01*
X1488686Y494087D01*
X1487446Y493879D01*
G01X1496746D02*
Y506379D01*
X1500466D01*
X1501706Y505754D01*
X1502636Y504296D01*
X1502946Y502629D01*
X1502636Y500962D01*
X1501861Y499712D01*
X1500466Y499087D01*
X1496746D01*
G01X1524646Y506379D02*
Y493879D01*
G01X1522476Y502212D02*
X1526816D01*
G01X1537046Y493879D02*
X1536116Y494087D01*
X1535186Y494920D01*
X1534566Y496379D01*
X1534256Y498046D01*
X1534566Y499712D01*
X1535186Y501171D01*
X1536116Y502004D01*
X1537046Y502212D01*
X1537976Y502004D01*
X1538906Y501171D01*
X1539526Y499712D01*
X1539681Y498046D01*
X1539526Y496379D01*
X1538906Y494920D01*
X1537976Y494087D01*
X1537046Y493879D01*
G01X1563086Y500546D02*
X1563706Y501171D01*
X1564171Y502212D01*
X1564481Y503671D01*
X1564171Y504921D01*
X1563551Y505754D01*
X1562466Y506379D01*
X1558281D01*
Y493879D01*
X1563396D01*
X1564481Y494712D01*
X1565101Y495962D01*
X1565411Y497421D01*
X1565101Y498879D01*
X1564171Y500129D01*
X1563086Y500546D01*
X1558281D01*
G01X1574246Y493879D02*
X1573006Y494087D01*
X1571921Y494920D01*
X1570991Y496171D01*
X1570371Y497629D01*
X1570061Y499296D01*
Y500962D01*
X1570371Y502629D01*
X1570991Y504087D01*
X1571921Y505337D01*
X1573006Y506171D01*
X1574246Y506379D01*
X1575486Y506171D01*
X1576571Y505337D01*
X1577501Y504087D01*
X1578121Y502629D01*
X1578431Y500962D01*
Y499296D01*
X1578121Y497629D01*
X1577501Y496171D01*
X1576571Y494920D01*
X1575486Y494087D01*
X1574246Y493879D01*
G01X1586646Y506379D02*
Y493879D01*
G01X1583081Y506379D02*
X1590211D01*
G01X1599046D02*
Y493879D01*
G01X1595481Y506379D02*
X1602611D01*
G01X1611446Y493879D02*
X1610206Y494087D01*
X1609121Y494920D01*
X1608191Y496171D01*
X1607571Y497629D01*
X1607261Y499296D01*
Y500962D01*
X1607571Y502629D01*
X1608191Y504087D01*
X1609121Y505337D01*
X1610206Y506171D01*
X1611446Y506379D01*
X1612686Y506171D01*
X1613771Y505337D01*
X1614701Y504087D01*
X1615321Y502629D01*
X1615631Y500962D01*
Y499296D01*
X1615321Y497629D01*
X1614701Y496171D01*
X1613771Y494920D01*
X1612686Y494087D01*
X1611446Y493879D01*
G01X1619816D02*
Y506379D01*
X1623846Y495962D01*
X1627876Y506379D01*
Y493879D01*
G01X1392896Y186329D02*
X1393981Y186537D01*
X1395221Y187162D01*
X1395996Y188204D01*
X1396306Y189662D01*
X1395996Y191120D01*
X1395066Y192371D01*
X1393671Y192996D01*
X1392121D01*
X1391191Y193412D01*
X1390416Y194454D01*
X1390106Y195912D01*
X1390571Y197371D01*
X1391656Y198412D01*
X1392896Y198829D01*
X1394136Y198412D01*
X1395221Y197371D01*
X1395686Y195912D01*
X1395376Y194454D01*
X1394601Y193412D01*
X1393671Y192996D01*
X1392121D01*
X1390726Y192371D01*
X1389796Y191120D01*
X1389486Y189662D01*
X1389796Y188204D01*
X1390571Y187162D01*
X1391811Y186537D01*
X1392896Y186329D01*
G01X1404986D02*
X1405296Y189037D01*
X1405761Y191329D01*
X1406381Y193412D01*
X1407156Y195704D01*
X1408396Y198829D01*
X1402196D01*
G01X1417696Y185912D02*
X1417386Y186121D01*
Y186537D01*
X1417696Y186746D01*
X1418006Y186537D01*
Y186121D01*
X1417696Y185912D01*
G01X1430096Y198829D02*
X1428856Y198412D01*
X1427926Y197371D01*
X1427306Y196121D01*
X1426841Y194454D01*
X1426686Y192579D01*
X1426841Y190704D01*
X1427306Y189037D01*
X1427926Y187787D01*
X1428856Y186746D01*
X1430096Y186329D01*
X1431336Y186746D01*
X1432266Y187787D01*
X1432886Y189037D01*
X1433351Y190704D01*
X1433506Y192579D01*
X1433351Y194454D01*
X1432886Y196121D01*
X1432266Y197371D01*
X1431336Y198412D01*
X1430096Y198829D01*
G01X1386696Y158229D02*
Y170729D01*
X1384836Y168229D01*
G01Y158229D02*
X1388556D01*
G01X1400956D02*
Y170729D01*
X1395221Y161771D01*
X1402971D01*
G01X1408551Y163437D02*
X1409636Y164896D01*
X1410566Y165729D01*
X1411806Y166146D01*
X1412891Y165729D01*
X1413666Y164896D01*
X1414286Y163646D01*
X1414441Y162187D01*
X1414286Y160937D01*
X1413666Y159687D01*
X1412736Y158646D01*
X1411651Y158229D01*
X1410411Y158646D01*
X1409326Y159895D01*
X1408706Y161771D01*
X1408551Y163854D01*
X1408861Y166562D01*
X1409326Y168021D01*
X1410101Y169479D01*
X1411186Y170521D01*
X1412271Y170729D01*
X1413356Y170312D01*
X1414131Y169271D01*
G01X1423896Y157812D02*
X1423586Y158021D01*
Y158437D01*
X1423896Y158646D01*
X1424206Y158437D01*
Y158021D01*
X1423896Y157812D01*
G01X1436296Y170729D02*
X1435056Y170312D01*
X1434126Y169271D01*
X1433506Y168021D01*
X1433041Y166354D01*
X1432886Y164479D01*
X1433041Y162604D01*
X1433506Y160937D01*
X1434126Y159687D01*
X1435056Y158646D01*
X1436296Y158229D01*
X1437536Y158646D01*
X1438466Y159687D01*
X1439086Y160937D01*
X1439551Y162604D01*
X1439706Y164479D01*
X1439551Y166354D01*
X1439086Y168021D01*
X1438466Y169271D01*
X1437536Y170312D01*
X1436296Y170729D01*
G01X1361586Y130129D02*
X1361896Y132837D01*
X1362361Y135129D01*
X1362981Y137212D01*
X1363756Y139504D01*
X1364996Y142629D01*
X1358796D01*
G01X1370886Y132004D02*
X1371816Y130962D01*
X1372901Y130337D01*
X1374296Y130129D01*
X1375691Y130546D01*
X1376776Y131379D01*
X1377551Y132837D01*
X1377706Y134504D01*
X1377396Y136171D01*
X1376621Y137212D01*
X1375536Y138046D01*
X1374451Y138254D01*
X1373366Y138046D01*
X1371971Y137212D01*
X1372436Y142629D01*
X1376621D01*
G01X1386696Y129712D02*
X1386386Y129921D01*
Y130337D01*
X1386696Y130546D01*
X1387006Y130337D01*
Y129921D01*
X1386696Y129712D01*
G01X1399096Y142629D02*
X1397856Y142212D01*
X1396926Y141171D01*
X1396306Y139921D01*
X1395841Y138254D01*
X1395686Y136379D01*
X1395841Y134504D01*
X1396306Y132837D01*
X1396926Y131587D01*
X1397856Y130546D01*
X1399096Y130129D01*
X1400336Y130546D01*
X1401266Y131587D01*
X1401886Y132837D01*
X1402351Y134504D01*
X1402506Y136379D01*
X1402351Y138254D01*
X1401886Y139921D01*
X1401266Y141171D01*
X1400336Y142212D01*
X1399096Y142629D01*
G01X1409171Y138462D02*
X1413821Y130129D01*
G01Y138462D02*
X1409171Y130129D01*
G01X1420486Y132629D02*
X1421416Y131170D01*
X1422656Y130337D01*
X1424051Y130129D01*
X1425291Y130337D01*
X1426531Y131379D01*
X1427306Y132629D01*
X1427461Y133879D01*
X1427151Y135337D01*
X1426066Y136379D01*
X1424981Y136796D01*
X1423586D01*
G01X1424981D02*
X1425911Y137421D01*
X1426686Y138462D01*
X1426996Y139712D01*
X1426686Y140962D01*
X1425911Y142004D01*
X1424516Y142629D01*
X1423121Y142421D01*
X1421726Y141587D01*
G01X1433351Y140546D02*
X1434281Y141795D01*
X1435366Y142421D01*
X1436606Y142629D01*
X1438156Y142212D01*
X1439241Y141171D01*
X1439551Y139921D01*
X1439396Y138670D01*
X1438776Y137629D01*
X1435676Y135546D01*
X1434281Y134087D01*
X1433351Y132004D01*
X1433041Y130129D01*
X1439551D01*
G01X1448696Y129712D02*
X1448386Y129921D01*
Y130337D01*
X1448696Y130546D01*
X1449006Y130337D01*
Y129921D01*
X1448696Y129712D01*
G01X1461096Y142629D02*
X1459856Y142212D01*
X1458926Y141171D01*
X1458306Y139921D01*
X1457841Y138254D01*
X1457686Y136379D01*
X1457841Y134504D01*
X1458306Y132837D01*
X1458926Y131587D01*
X1459856Y130546D01*
X1461096Y130129D01*
X1462336Y130546D01*
X1463266Y131587D01*
X1463886Y132837D01*
X1464351Y134504D01*
X1464506Y136379D01*
X1464351Y138254D01*
X1463886Y139921D01*
X1463266Y141171D01*
X1462336Y142212D01*
X1461096Y142629D01*
G01X1392586Y242529D02*
X1392896Y245237D01*
X1393361Y247529D01*
X1393981Y249612D01*
X1394756Y251904D01*
X1395996Y255029D01*
X1389796D01*
G01X1401886Y245029D02*
X1402816Y243570D01*
X1404056Y242737D01*
X1405451Y242529D01*
X1406691Y242737D01*
X1407931Y243779D01*
X1408706Y245029D01*
X1408861Y246279D01*
X1408551Y247737D01*
X1407466Y248779D01*
X1406381Y249196D01*
X1404986D01*
G01X1406381D02*
X1407311Y249821D01*
X1408086Y250862D01*
X1408396Y252112D01*
X1408086Y253362D01*
X1407311Y254404D01*
X1405916Y255029D01*
X1404521Y254821D01*
X1403126Y253987D01*
G01X1417696Y242112D02*
X1417386Y242321D01*
Y242737D01*
X1417696Y242946D01*
X1418006Y242737D01*
Y242321D01*
X1417696Y242112D01*
G01X1430096Y255029D02*
X1428856Y254612D01*
X1427926Y253571D01*
X1427306Y252321D01*
X1426841Y250654D01*
X1426686Y248779D01*
X1426841Y246904D01*
X1427306Y245237D01*
X1427926Y243987D01*
X1428856Y242946D01*
X1430096Y242529D01*
X1431336Y242946D01*
X1432266Y243987D01*
X1432886Y245237D01*
X1433351Y246904D01*
X1433506Y248779D01*
X1433351Y250654D01*
X1432886Y252321D01*
X1432266Y253571D01*
X1431336Y254612D01*
X1430096Y255029D01*
G01X1392896Y214429D02*
X1393981Y214637D01*
X1395221Y215262D01*
X1395996Y216304D01*
X1396306Y217762D01*
X1395996Y219220D01*
X1395066Y220471D01*
X1393671Y221096D01*
X1392121D01*
X1391191Y221512D01*
X1390416Y222554D01*
X1390106Y224012D01*
X1390571Y225471D01*
X1391656Y226512D01*
X1392896Y226929D01*
X1394136Y226512D01*
X1395221Y225471D01*
X1395686Y224012D01*
X1395376Y222554D01*
X1394601Y221512D01*
X1393671Y221096D01*
X1392121D01*
X1390726Y220471D01*
X1389796Y219220D01*
X1389486Y217762D01*
X1389796Y216304D01*
X1390571Y215262D01*
X1391811Y214637D01*
X1392896Y214429D01*
G01X1402351Y219637D02*
X1403436Y221096D01*
X1404366Y221929D01*
X1405606Y222346D01*
X1406691Y221929D01*
X1407466Y221096D01*
X1408086Y219846D01*
X1408241Y218387D01*
X1408086Y217137D01*
X1407466Y215887D01*
X1406536Y214846D01*
X1405451Y214429D01*
X1404211Y214846D01*
X1403126Y216095D01*
X1402506Y217971D01*
X1402351Y220054D01*
X1402661Y222762D01*
X1403126Y224221D01*
X1403901Y225679D01*
X1404986Y226721D01*
X1406071Y226929D01*
X1407156Y226512D01*
X1407931Y225471D01*
G01X1417696Y214012D02*
X1417386Y214221D01*
Y214637D01*
X1417696Y214846D01*
X1418006Y214637D01*
Y214221D01*
X1417696Y214012D01*
G01X1430096Y226929D02*
X1428856Y226512D01*
X1427926Y225471D01*
X1427306Y224221D01*
X1426841Y222554D01*
X1426686Y220679D01*
X1426841Y218804D01*
X1427306Y217137D01*
X1427926Y215887D01*
X1428856Y214846D01*
X1430096Y214429D01*
X1431336Y214846D01*
X1432266Y215887D01*
X1432886Y217137D01*
X1433351Y218804D01*
X1433506Y220679D01*
X1433351Y222554D01*
X1432886Y224221D01*
X1432266Y225471D01*
X1431336Y226512D01*
X1430096Y226929D01*
G01X1389951Y337246D02*
X1390881Y338495D01*
X1391966Y339121D01*
X1393206Y339329D01*
X1394756Y338912D01*
X1395841Y337871D01*
X1396151Y336621D01*
X1395996Y335370D01*
X1395376Y334329D01*
X1392276Y332246D01*
X1390881Y330787D01*
X1389951Y328704D01*
X1389641Y326829D01*
X1396151D01*
G01X1405296Y339329D02*
X1404056Y338912D01*
X1403126Y337871D01*
X1402506Y336621D01*
X1402041Y334954D01*
X1401886Y333079D01*
X1402041Y331204D01*
X1402506Y329537D01*
X1403126Y328287D01*
X1404056Y327246D01*
X1405296Y326829D01*
X1406536Y327246D01*
X1407466Y328287D01*
X1408086Y329537D01*
X1408551Y331204D01*
X1408706Y333079D01*
X1408551Y334954D01*
X1408086Y336621D01*
X1407466Y337871D01*
X1406536Y338912D01*
X1405296Y339329D01*
G01X1417696Y326412D02*
X1417386Y326621D01*
Y327037D01*
X1417696Y327246D01*
X1418006Y327037D01*
Y326621D01*
X1417696Y326412D01*
G01X1430096Y339329D02*
X1428856Y338912D01*
X1427926Y337871D01*
X1427306Y336621D01*
X1426841Y334954D01*
X1426686Y333079D01*
X1426841Y331204D01*
X1427306Y329537D01*
X1427926Y328287D01*
X1428856Y327246D01*
X1430096Y326829D01*
X1431336Y327246D01*
X1432266Y328287D01*
X1432886Y329537D01*
X1433351Y331204D01*
X1433506Y333079D01*
X1433351Y334954D01*
X1432886Y336621D01*
X1432266Y337871D01*
X1431336Y338912D01*
X1430096Y339329D01*
G01X1386696Y298729D02*
Y311229D01*
X1384836Y308729D01*
G01Y298729D02*
X1388556D01*
G01X1400956D02*
Y311229D01*
X1395221Y302271D01*
X1402971D01*
G01X1411496Y311229D02*
X1410256Y310812D01*
X1409326Y309771D01*
X1408706Y308521D01*
X1408241Y306854D01*
X1408086Y304979D01*
X1408241Y303104D01*
X1408706Y301437D01*
X1409326Y300187D01*
X1410256Y299146D01*
X1411496Y298729D01*
X1412736Y299146D01*
X1413666Y300187D01*
X1414286Y301437D01*
X1414751Y303104D01*
X1414906Y304979D01*
X1414751Y306854D01*
X1414286Y308521D01*
X1413666Y309771D01*
X1412736Y310812D01*
X1411496Y311229D01*
G01X1423896Y298312D02*
X1423586Y298521D01*
Y298937D01*
X1423896Y299146D01*
X1424206Y298937D01*
Y298521D01*
X1423896Y298312D01*
G01X1436296Y311229D02*
X1435056Y310812D01*
X1434126Y309771D01*
X1433506Y308521D01*
X1433041Y306854D01*
X1432886Y304979D01*
X1433041Y303104D01*
X1433506Y301437D01*
X1434126Y300187D01*
X1435056Y299146D01*
X1436296Y298729D01*
X1437536Y299146D01*
X1438466Y300187D01*
X1439086Y301437D01*
X1439551Y303104D01*
X1439706Y304979D01*
X1439551Y306854D01*
X1439086Y308521D01*
X1438466Y309771D01*
X1437536Y310812D01*
X1436296Y311229D01*
G01X1377396Y270629D02*
X1371196D01*
Y283129D01*
X1377396D01*
G01X1374916Y277087D02*
X1371196D01*
G01X1383596Y283129D02*
Y270629D01*
X1389796D01*
G01X1395996Y283129D02*
Y270629D01*
X1402196D01*
G01X1409636Y283129D02*
X1413356D01*
G01X1411496D02*
Y270629D01*
G01X1409636D02*
X1413356D01*
G01X1420796D02*
Y283129D01*
X1424516D01*
X1425756Y282504D01*
X1426686Y281046D01*
X1426996Y279379D01*
X1426686Y277712D01*
X1425911Y276462D01*
X1424516Y275837D01*
X1420796D01*
G01X1433041Y272295D02*
X1434281Y271254D01*
X1435676Y270629D01*
X1436916D01*
X1438156Y271254D01*
X1439086Y272295D01*
X1439551Y273754D01*
X1439241Y275212D01*
X1438466Y276462D01*
X1437071Y277296D01*
X1435211Y277712D01*
X1434126Y278546D01*
X1433661Y280004D01*
X1433971Y281462D01*
X1434746Y282504D01*
X1435831Y283129D01*
X1436916D01*
X1438001Y282712D01*
X1438931Y281671D01*
G01X1451796Y270629D02*
X1445596D01*
Y283129D01*
X1451796D01*
G01X1449316Y277087D02*
X1445596D01*
G01X1392896Y411129D02*
Y423629D01*
X1391036Y421129D01*
G01Y411129D02*
X1394756D01*
G01X1405296Y423629D02*
X1404056Y423212D01*
X1403126Y422171D01*
X1402506Y420921D01*
X1402041Y419254D01*
X1401886Y417379D01*
X1402041Y415504D01*
X1402506Y413837D01*
X1403126Y412587D01*
X1404056Y411546D01*
X1405296Y411129D01*
X1406536Y411546D01*
X1407466Y412587D01*
X1408086Y413837D01*
X1408551Y415504D01*
X1408706Y417379D01*
X1408551Y419254D01*
X1408086Y420921D01*
X1407466Y422171D01*
X1406536Y423212D01*
X1405296Y423629D01*
G01X1417696Y410712D02*
X1417386Y410921D01*
Y411337D01*
X1417696Y411546D01*
X1418006Y411337D01*
Y410921D01*
X1417696Y410712D01*
G01X1430096Y423629D02*
X1428856Y423212D01*
X1427926Y422171D01*
X1427306Y420921D01*
X1426841Y419254D01*
X1426686Y417379D01*
X1426841Y415504D01*
X1427306Y413837D01*
X1427926Y412587D01*
X1428856Y411546D01*
X1430096Y411129D01*
X1431336Y411546D01*
X1432266Y412587D01*
X1432886Y413837D01*
X1433351Y415504D01*
X1433506Y417379D01*
X1433351Y419254D01*
X1432886Y420921D01*
X1432266Y422171D01*
X1431336Y423212D01*
X1430096Y423629D01*
G01X1392896Y383029D02*
Y395529D01*
X1391036Y393029D01*
G01Y383029D02*
X1394756D01*
G01X1402351Y393446D02*
X1403281Y394695D01*
X1404366Y395321D01*
X1405606Y395529D01*
X1407156Y395112D01*
X1408241Y394071D01*
X1408551Y392821D01*
X1408396Y391570D01*
X1407776Y390529D01*
X1404676Y388446D01*
X1403281Y386987D01*
X1402351Y384904D01*
X1402041Y383029D01*
X1408551D01*
G01X1417696Y382612D02*
X1417386Y382821D01*
Y383237D01*
X1417696Y383446D01*
X1418006Y383237D01*
Y382821D01*
X1417696Y382612D01*
G01X1430096Y395529D02*
X1428856Y395112D01*
X1427926Y394071D01*
X1427306Y392821D01*
X1426841Y391154D01*
X1426686Y389279D01*
X1426841Y387404D01*
X1427306Y385737D01*
X1427926Y384487D01*
X1428856Y383446D01*
X1430096Y383029D01*
X1431336Y383446D01*
X1432266Y384487D01*
X1432886Y385737D01*
X1433351Y387404D01*
X1433506Y389279D01*
X1433351Y391154D01*
X1432886Y392821D01*
X1432266Y394071D01*
X1431336Y395112D01*
X1430096Y395529D01*
G01X1392896Y354929D02*
Y367429D01*
X1391036Y364929D01*
G01Y354929D02*
X1394756D01*
G01X1402351Y360137D02*
X1403436Y361596D01*
X1404366Y362429D01*
X1405606Y362846D01*
X1406691Y362429D01*
X1407466Y361596D01*
X1408086Y360346D01*
X1408241Y358887D01*
X1408086Y357637D01*
X1407466Y356387D01*
X1406536Y355346D01*
X1405451Y354929D01*
X1404211Y355346D01*
X1403126Y356595D01*
X1402506Y358471D01*
X1402351Y360554D01*
X1402661Y363262D01*
X1403126Y364721D01*
X1403901Y366179D01*
X1404986Y367221D01*
X1406071Y367429D01*
X1407156Y367012D01*
X1407931Y365971D01*
G01X1417696Y354512D02*
X1417386Y354721D01*
Y355137D01*
X1417696Y355346D01*
X1418006Y355137D01*
Y354721D01*
X1417696Y354512D01*
G01X1430096Y367429D02*
X1428856Y367012D01*
X1427926Y365971D01*
X1427306Y364721D01*
X1426841Y363054D01*
X1426686Y361179D01*
X1426841Y359304D01*
X1427306Y357637D01*
X1427926Y356387D01*
X1428856Y355346D01*
X1430096Y354929D01*
X1431336Y355346D01*
X1432266Y356387D01*
X1432886Y357637D01*
X1433351Y359304D01*
X1433506Y361179D01*
X1433351Y363054D01*
X1432886Y364721D01*
X1432266Y365971D01*
X1431336Y367012D01*
X1430096Y367429D01*
G01X1389641Y442445D02*
X1390881Y441404D01*
X1392276Y440779D01*
X1393516D01*
X1394756Y441404D01*
X1395686Y442445D01*
X1396151Y443904D01*
X1395841Y445362D01*
X1395066Y446612D01*
X1393671Y447446D01*
X1391811Y447862D01*
X1390726Y448696D01*
X1390261Y450154D01*
X1390571Y451612D01*
X1391346Y452654D01*
X1392431Y453279D01*
X1393516D01*
X1394601Y452862D01*
X1395531Y451821D01*
G01X1403436Y453279D02*
X1407156D01*
G01X1405296D02*
Y440779D01*
G01X1403436D02*
X1407156D01*
G01X1414751Y453279D02*
X1420641D01*
X1414751Y440779D01*
X1420641D01*
G01X1433196D02*
X1426996D01*
Y453279D01*
X1433196D01*
G01X1430716Y447237D02*
X1426996D01*
G01X1510231Y186329D02*
Y198829D01*
X1517361Y186329D01*
Y198829D01*
G01X1526196Y186329D02*
X1524956Y186537D01*
X1523871Y187370D01*
X1522941Y188621D01*
X1522321Y190079D01*
X1522011Y191746D01*
Y193412D01*
X1522321Y195079D01*
X1522941Y196537D01*
X1523871Y197787D01*
X1524956Y198621D01*
X1526196Y198829D01*
X1527436Y198621D01*
X1528521Y197787D01*
X1529451Y196537D01*
X1530071Y195079D01*
X1530381Y193412D01*
Y191746D01*
X1530071Y190079D01*
X1529451Y188621D01*
X1528521Y187370D01*
X1527436Y186537D01*
X1526196Y186329D01*
G01X1535031D02*
Y198829D01*
X1542161Y186329D01*
Y198829D01*
G01X1548981Y190496D02*
X1553011D01*
G01X1560296Y186329D02*
Y198829D01*
X1564016D01*
X1565256Y198204D01*
X1566186Y196746D01*
X1566496Y195079D01*
X1566186Y193412D01*
X1565411Y192162D01*
X1564016Y191537D01*
X1560296D01*
G01X1572696Y198829D02*
Y186329D01*
X1578896D01*
G01X1584321D02*
X1588196Y198829D01*
X1592071Y186329D01*
G01X1590676Y190704D02*
X1585716D01*
G01X1600596Y198829D02*
Y186329D01*
G01X1597031Y198829D02*
X1604161D01*
G01X1616096Y186329D02*
X1609896D01*
Y198829D01*
X1616096D01*
G01X1613616Y192787D02*
X1609896D01*
G01X1621986Y186329D02*
Y198829D01*
X1625086D01*
X1626326Y198204D01*
X1627256Y197371D01*
X1628031Y196121D01*
X1628651Y194662D01*
X1628806Y192579D01*
X1628651Y190496D01*
X1628031Y189037D01*
X1627256Y187787D01*
X1626326Y186954D01*
X1625086Y186329D01*
X1621986D01*
G01X1510231Y158229D02*
Y170729D01*
X1517361Y158229D01*
Y170729D01*
G01X1526196Y158229D02*
X1524956Y158437D01*
X1523871Y159270D01*
X1522941Y160521D01*
X1522321Y161979D01*
X1522011Y163646D01*
Y165312D01*
X1522321Y166979D01*
X1522941Y168437D01*
X1523871Y169687D01*
X1524956Y170521D01*
X1526196Y170729D01*
X1527436Y170521D01*
X1528521Y169687D01*
X1529451Y168437D01*
X1530071Y166979D01*
X1530381Y165312D01*
Y163646D01*
X1530071Y161979D01*
X1529451Y160521D01*
X1528521Y159270D01*
X1527436Y158437D01*
X1526196Y158229D01*
G01X1535031D02*
Y170729D01*
X1542161Y158229D01*
Y170729D01*
G01X1548981Y162396D02*
X1553011D01*
G01X1560296Y158229D02*
Y170729D01*
X1564016D01*
X1565256Y170104D01*
X1566186Y168646D01*
X1566496Y166979D01*
X1566186Y165312D01*
X1565411Y164062D01*
X1564016Y163437D01*
X1560296D01*
G01X1572696Y170729D02*
Y158229D01*
X1578896D01*
G01X1584321D02*
X1588196Y170729D01*
X1592071Y158229D01*
G01X1590676Y162604D02*
X1585716D01*
G01X1600596Y170729D02*
Y158229D01*
G01X1597031Y170729D02*
X1604161D01*
G01X1616096Y158229D02*
X1609896D01*
Y170729D01*
X1616096D01*
G01X1613616Y164687D02*
X1609896D01*
G01X1621986Y158229D02*
Y170729D01*
X1625086D01*
X1626326Y170104D01*
X1627256Y169271D01*
X1628031Y168021D01*
X1628651Y166562D01*
X1628806Y164479D01*
X1628651Y162396D01*
X1628031Y160937D01*
X1627256Y159687D01*
X1626326Y158854D01*
X1625086Y158229D01*
X1621986D01*
G01X1535496Y130129D02*
Y142629D01*
X1539216D01*
X1540456Y142004D01*
X1541386Y140546D01*
X1541696Y138879D01*
X1541386Y137212D01*
X1540611Y135962D01*
X1539216Y135337D01*
X1535496D01*
G01X1547896Y142629D02*
Y130129D01*
X1554096D01*
G01X1559521D02*
X1563396Y142629D01*
X1567271Y130129D01*
G01X1565876Y134504D02*
X1560916D01*
G01X1575796Y142629D02*
Y130129D01*
G01X1572231Y142629D02*
X1579361D01*
G01X1591296Y130129D02*
X1585096D01*
Y142629D01*
X1591296D01*
G01X1588816Y136587D02*
X1585096D01*
G01X1597186Y130129D02*
Y142629D01*
X1600286D01*
X1601526Y142004D01*
X1602456Y141171D01*
X1603231Y139921D01*
X1603851Y138462D01*
X1604006Y136379D01*
X1603851Y134296D01*
X1603231Y132837D01*
X1602456Y131587D01*
X1601526Y130754D01*
X1600286Y130129D01*
X1597186D01*
G01X1506046Y459529D02*
Y122329D01*
G01X1510231Y242529D02*
Y255029D01*
X1517361Y242529D01*
Y255029D01*
G01X1526196Y242529D02*
X1524956Y242737D01*
X1523871Y243570D01*
X1522941Y244821D01*
X1522321Y246279D01*
X1522011Y247946D01*
Y249612D01*
X1522321Y251279D01*
X1522941Y252737D01*
X1523871Y253987D01*
X1524956Y254821D01*
X1526196Y255029D01*
X1527436Y254821D01*
X1528521Y253987D01*
X1529451Y252737D01*
X1530071Y251279D01*
X1530381Y249612D01*
Y247946D01*
X1530071Y246279D01*
X1529451Y244821D01*
X1528521Y243570D01*
X1527436Y242737D01*
X1526196Y242529D01*
G01X1535031D02*
Y255029D01*
X1542161Y242529D01*
Y255029D01*
G01X1548981Y246696D02*
X1553011D01*
G01X1560296Y242529D02*
Y255029D01*
X1564016D01*
X1565256Y254404D01*
X1566186Y252946D01*
X1566496Y251279D01*
X1566186Y249612D01*
X1565411Y248362D01*
X1564016Y247737D01*
X1560296D01*
G01X1572696Y255029D02*
Y242529D01*
X1578896D01*
G01X1584321D02*
X1588196Y255029D01*
X1592071Y242529D01*
G01X1590676Y246904D02*
X1585716D01*
G01X1600596Y255029D02*
Y242529D01*
G01X1597031Y255029D02*
X1604161D01*
G01X1616096Y242529D02*
X1609896D01*
Y255029D01*
X1616096D01*
G01X1613616Y248987D02*
X1609896D01*
G01X1621986Y242529D02*
Y255029D01*
X1625086D01*
X1626326Y254404D01*
X1627256Y253571D01*
X1628031Y252321D01*
X1628651Y250862D01*
X1628806Y248779D01*
X1628651Y246696D01*
X1628031Y245237D01*
X1627256Y243987D01*
X1626326Y243154D01*
X1625086Y242529D01*
X1621986D01*
G01X1510231Y214429D02*
Y226929D01*
X1517361Y214429D01*
Y226929D01*
G01X1526196Y214429D02*
X1524956Y214637D01*
X1523871Y215470D01*
X1522941Y216721D01*
X1522321Y218179D01*
X1522011Y219846D01*
Y221512D01*
X1522321Y223179D01*
X1522941Y224637D01*
X1523871Y225887D01*
X1524956Y226721D01*
X1526196Y226929D01*
X1527436Y226721D01*
X1528521Y225887D01*
X1529451Y224637D01*
X1530071Y223179D01*
X1530381Y221512D01*
Y219846D01*
X1530071Y218179D01*
X1529451Y216721D01*
X1528521Y215470D01*
X1527436Y214637D01*
X1526196Y214429D01*
G01X1535031D02*
Y226929D01*
X1542161Y214429D01*
Y226929D01*
G01X1548981Y218596D02*
X1553011D01*
G01X1560296Y214429D02*
Y226929D01*
X1564016D01*
X1565256Y226304D01*
X1566186Y224846D01*
X1566496Y223179D01*
X1566186Y221512D01*
X1565411Y220262D01*
X1564016Y219637D01*
X1560296D01*
G01X1572696Y226929D02*
Y214429D01*
X1578896D01*
G01X1584321D02*
X1588196Y226929D01*
X1592071Y214429D01*
G01X1590676Y218804D02*
X1585716D01*
G01X1600596Y226929D02*
Y214429D01*
G01X1597031Y226929D02*
X1604161D01*
G01X1616096Y214429D02*
X1609896D01*
Y226929D01*
X1616096D01*
G01X1613616Y220887D02*
X1609896D01*
G01X1621986Y214429D02*
Y226929D01*
X1625086D01*
X1626326Y226304D01*
X1627256Y225471D01*
X1628031Y224221D01*
X1628651Y222762D01*
X1628806Y220679D01*
X1628651Y218596D01*
X1628031Y217137D01*
X1627256Y215887D01*
X1626326Y215054D01*
X1625086Y214429D01*
X1621986D01*
G01X1535496Y326829D02*
Y339329D01*
X1539216D01*
X1540456Y338704D01*
X1541386Y337246D01*
X1541696Y335579D01*
X1541386Y333912D01*
X1540611Y332662D01*
X1539216Y332037D01*
X1535496D01*
G01X1547896Y339329D02*
Y326829D01*
X1554096D01*
G01X1559521D02*
X1563396Y339329D01*
X1567271Y326829D01*
G01X1565876Y331204D02*
X1560916D01*
G01X1575796Y339329D02*
Y326829D01*
G01X1572231Y339329D02*
X1579361D01*
G01X1591296Y326829D02*
X1585096D01*
Y339329D01*
X1591296D01*
G01X1588816Y333287D02*
X1585096D01*
G01X1597186Y326829D02*
Y339329D01*
X1600286D01*
X1601526Y338704D01*
X1602456Y337871D01*
X1603231Y336621D01*
X1603851Y335162D01*
X1604006Y333079D01*
X1603851Y330996D01*
X1603231Y329537D01*
X1602456Y328287D01*
X1601526Y327454D01*
X1600286Y326829D01*
X1597186D01*
G01X1535496Y298729D02*
Y311229D01*
X1539216D01*
X1540456Y310604D01*
X1541386Y309146D01*
X1541696Y307479D01*
X1541386Y305812D01*
X1540611Y304562D01*
X1539216Y303937D01*
X1535496D01*
G01X1547896Y311229D02*
Y298729D01*
X1554096D01*
G01X1559521D02*
X1563396Y311229D01*
X1567271Y298729D01*
G01X1565876Y303104D02*
X1560916D01*
G01X1575796Y311229D02*
Y298729D01*
G01X1572231Y311229D02*
X1579361D01*
G01X1591296Y298729D02*
X1585096D01*
Y311229D01*
X1591296D01*
G01X1588816Y305187D02*
X1585096D01*
G01X1597186Y298729D02*
Y311229D01*
X1600286D01*
X1601526Y310604D01*
X1602456Y309771D01*
X1603231Y308521D01*
X1603851Y307062D01*
X1604006Y304979D01*
X1603851Y302896D01*
X1603231Y301437D01*
X1602456Y300187D01*
X1601526Y299354D01*
X1600286Y298729D01*
X1597186D01*
G01X1510231Y270629D02*
Y283129D01*
X1517361Y270629D01*
Y283129D01*
G01X1526196Y270629D02*
X1524956Y270837D01*
X1523871Y271670D01*
X1522941Y272921D01*
X1522321Y274379D01*
X1522011Y276046D01*
Y277712D01*
X1522321Y279379D01*
X1522941Y280837D01*
X1523871Y282087D01*
X1524956Y282921D01*
X1526196Y283129D01*
X1527436Y282921D01*
X1528521Y282087D01*
X1529451Y280837D01*
X1530071Y279379D01*
X1530381Y277712D01*
Y276046D01*
X1530071Y274379D01*
X1529451Y272921D01*
X1528521Y271670D01*
X1527436Y270837D01*
X1526196Y270629D01*
G01X1535031D02*
Y283129D01*
X1542161Y270629D01*
Y283129D01*
G01X1548981Y274796D02*
X1553011D01*
G01X1560296Y270629D02*
Y283129D01*
X1564016D01*
X1565256Y282504D01*
X1566186Y281046D01*
X1566496Y279379D01*
X1566186Y277712D01*
X1565411Y276462D01*
X1564016Y275837D01*
X1560296D01*
G01X1572696Y283129D02*
Y270629D01*
X1578896D01*
G01X1584321D02*
X1588196Y283129D01*
X1592071Y270629D01*
G01X1590676Y275004D02*
X1585716D01*
G01X1600596Y283129D02*
Y270629D01*
G01X1597031Y283129D02*
X1604161D01*
G01X1616096Y270629D02*
X1609896D01*
Y283129D01*
X1616096D01*
G01X1613616Y277087D02*
X1609896D01*
G01X1621986Y270629D02*
Y283129D01*
X1625086D01*
X1626326Y282504D01*
X1627256Y281671D01*
X1628031Y280421D01*
X1628651Y278962D01*
X1628806Y276879D01*
X1628651Y274796D01*
X1628031Y273337D01*
X1627256Y272087D01*
X1626326Y271254D01*
X1625086Y270629D01*
X1621986D01*
G01X1535496Y411129D02*
Y423629D01*
X1539216D01*
X1540456Y423004D01*
X1541386Y421546D01*
X1541696Y419879D01*
X1541386Y418212D01*
X1540611Y416962D01*
X1539216Y416337D01*
X1535496D01*
G01X1547896Y423629D02*
Y411129D01*
X1554096D01*
G01X1559521D02*
X1563396Y423629D01*
X1567271Y411129D01*
G01X1565876Y415504D02*
X1560916D01*
G01X1575796Y423629D02*
Y411129D01*
G01X1572231Y423629D02*
X1579361D01*
G01X1591296Y411129D02*
X1585096D01*
Y423629D01*
X1591296D01*
G01X1588816Y417587D02*
X1585096D01*
G01X1597186Y411129D02*
Y423629D01*
X1600286D01*
X1601526Y423004D01*
X1602456Y422171D01*
X1603231Y420921D01*
X1603851Y419462D01*
X1604006Y417379D01*
X1603851Y415296D01*
X1603231Y413837D01*
X1602456Y412587D01*
X1601526Y411754D01*
X1600286Y411129D01*
X1597186D01*
G01X1535496Y383029D02*
Y395529D01*
X1539216D01*
X1540456Y394904D01*
X1541386Y393446D01*
X1541696Y391779D01*
X1541386Y390112D01*
X1540611Y388862D01*
X1539216Y388237D01*
X1535496D01*
G01X1547896Y395529D02*
Y383029D01*
X1554096D01*
G01X1559521D02*
X1563396Y395529D01*
X1567271Y383029D01*
G01X1565876Y387404D02*
X1560916D01*
G01X1575796Y395529D02*
Y383029D01*
G01X1572231Y395529D02*
X1579361D01*
G01X1591296Y383029D02*
X1585096D01*
Y395529D01*
X1591296D01*
G01X1588816Y389487D02*
X1585096D01*
G01X1597186Y383029D02*
Y395529D01*
X1600286D01*
X1601526Y394904D01*
X1602456Y394071D01*
X1603231Y392821D01*
X1603851Y391362D01*
X1604006Y389279D01*
X1603851Y387196D01*
X1603231Y385737D01*
X1602456Y384487D01*
X1601526Y383654D01*
X1600286Y383029D01*
X1597186D01*
G01X1535496Y354929D02*
Y367429D01*
X1539216D01*
X1540456Y366804D01*
X1541386Y365346D01*
X1541696Y363679D01*
X1541386Y362012D01*
X1540611Y360762D01*
X1539216Y360137D01*
X1535496D01*
G01X1547896Y367429D02*
Y354929D01*
X1554096D01*
G01X1559521D02*
X1563396Y367429D01*
X1567271Y354929D01*
G01X1565876Y359304D02*
X1560916D01*
G01X1575796Y367429D02*
Y354929D01*
G01X1572231Y367429D02*
X1579361D01*
G01X1591296Y354929D02*
X1585096D01*
Y367429D01*
X1591296D01*
G01X1588816Y361387D02*
X1585096D01*
G01X1597186Y354929D02*
Y367429D01*
X1600286D01*
X1601526Y366804D01*
X1602456Y365971D01*
X1603231Y364721D01*
X1603851Y363262D01*
X1604006Y361179D01*
X1603851Y359096D01*
X1603231Y357637D01*
X1602456Y356387D01*
X1601526Y355554D01*
X1600286Y354929D01*
X1597186D01*
G01X1535496Y440779D02*
Y453279D01*
X1539216D01*
X1540456Y452654D01*
X1541386Y451196D01*
X1541696Y449529D01*
X1541386Y447862D01*
X1540611Y446612D01*
X1539216Y445987D01*
X1535496D01*
G01X1547896Y453279D02*
Y440779D01*
X1554096D01*
G01X1559521D02*
X1563396Y453279D01*
X1567271Y440779D01*
G01X1565876Y445154D02*
X1560916D01*
G01X1575796Y453279D02*
Y440779D01*
G01X1572231Y453279D02*
X1579361D01*
G01X1591296Y440779D02*
X1585096D01*
Y453279D01*
X1591296D01*
G01X1588816Y447237D02*
X1585096D01*
G01X1597186Y440779D02*
Y453279D01*
X1600286D01*
X1601526Y452654D01*
X1602456Y451821D01*
X1603231Y450571D01*
X1603851Y449112D01*
X1604006Y447029D01*
X1603851Y444946D01*
X1603231Y443487D01*
X1602456Y442237D01*
X1601526Y441404D01*
X1600286Y440779D01*
X1597186D01*
G01X1633146Y459529D02*
Y122329D01*
G01X1668951Y191537D02*
X1670036Y192996D01*
X1670966Y193829D01*
X1672206Y194246D01*
X1673291Y193829D01*
X1674066Y192996D01*
X1674686Y191746D01*
X1674841Y190287D01*
X1674686Y189037D01*
X1674066Y187787D01*
X1673136Y186746D01*
X1672051Y186329D01*
X1670811Y186746D01*
X1669726Y187995D01*
X1669106Y189871D01*
X1668951Y191954D01*
X1669261Y194662D01*
X1669726Y196121D01*
X1670501Y197579D01*
X1671586Y198621D01*
X1672671Y198829D01*
X1673756Y198412D01*
X1674531Y197371D01*
G01X1668951Y168646D02*
X1669881Y169895D01*
X1670966Y170521D01*
X1672206Y170729D01*
X1673756Y170312D01*
X1674841Y169271D01*
X1675151Y168021D01*
X1674996Y166770D01*
X1674376Y165729D01*
X1671276Y163646D01*
X1669881Y162187D01*
X1668951Y160104D01*
X1668641Y158229D01*
X1675151D01*
G01X1662286Y132629D02*
X1663216Y131170D01*
X1664456Y130337D01*
X1665851Y130129D01*
X1667091Y130337D01*
X1668331Y131379D01*
X1669106Y132629D01*
X1669261Y133879D01*
X1668951Y135337D01*
X1667866Y136379D01*
X1666781Y136796D01*
X1665386D01*
G01X1666781D02*
X1667711Y137421D01*
X1668486Y138462D01*
X1668796Y139712D01*
X1668486Y140962D01*
X1667711Y142004D01*
X1666316Y142629D01*
X1664921Y142421D01*
X1663526Y141587D01*
G01X1678096Y142629D02*
X1676856Y142212D01*
X1675926Y141171D01*
X1675306Y139921D01*
X1674841Y138254D01*
X1674686Y136379D01*
X1674841Y134504D01*
X1675306Y132837D01*
X1675926Y131587D01*
X1676856Y130546D01*
X1678096Y130129D01*
X1679336Y130546D01*
X1680266Y131587D01*
X1680886Y132837D01*
X1681351Y134504D01*
X1681506Y136379D01*
X1681351Y138254D01*
X1680886Y139921D01*
X1680266Y141171D01*
X1679336Y142212D01*
X1678096Y142629D01*
G01X1662286Y245029D02*
X1663216Y243570D01*
X1664456Y242737D01*
X1665851Y242529D01*
X1667091Y242737D01*
X1668331Y243779D01*
X1669106Y245029D01*
X1669261Y246279D01*
X1668951Y247737D01*
X1667866Y248779D01*
X1666781Y249196D01*
X1665386D01*
G01X1666781D02*
X1667711Y249821D01*
X1668486Y250862D01*
X1668796Y252112D01*
X1668486Y253362D01*
X1667711Y254404D01*
X1666316Y255029D01*
X1664921Y254821D01*
X1663526Y253987D01*
G01X1678096Y255029D02*
X1676856Y254612D01*
X1675926Y253571D01*
X1675306Y252321D01*
X1674841Y250654D01*
X1674686Y248779D01*
X1674841Y246904D01*
X1675306Y245237D01*
X1675926Y243987D01*
X1676856Y242946D01*
X1678096Y242529D01*
X1679336Y242946D01*
X1680266Y243987D01*
X1680886Y245237D01*
X1681351Y246904D01*
X1681506Y248779D01*
X1681351Y250654D01*
X1680886Y252321D01*
X1680266Y253571D01*
X1679336Y254612D01*
X1678096Y255029D01*
G01X1671896Y214429D02*
X1672981Y214637D01*
X1674221Y215262D01*
X1674996Y216304D01*
X1675306Y217762D01*
X1674996Y219220D01*
X1674066Y220471D01*
X1672671Y221096D01*
X1671121D01*
X1670191Y221512D01*
X1669416Y222554D01*
X1669106Y224012D01*
X1669571Y225471D01*
X1670656Y226512D01*
X1671896Y226929D01*
X1673136Y226512D01*
X1674221Y225471D01*
X1674686Y224012D01*
X1674376Y222554D01*
X1673601Y221512D01*
X1672671Y221096D01*
X1671121D01*
X1669726Y220471D01*
X1668796Y219220D01*
X1668486Y217762D01*
X1668796Y216304D01*
X1669571Y215262D01*
X1670811Y214637D01*
X1671896Y214429D01*
G01X1662751Y332037D02*
X1663836Y333496D01*
X1664766Y334329D01*
X1666006Y334746D01*
X1667091Y334329D01*
X1667866Y333496D01*
X1668486Y332246D01*
X1668641Y330787D01*
X1668486Y329537D01*
X1667866Y328287D01*
X1666936Y327246D01*
X1665851Y326829D01*
X1664611Y327246D01*
X1663526Y328495D01*
X1662906Y330371D01*
X1662751Y332454D01*
X1663061Y335162D01*
X1663526Y336621D01*
X1664301Y338079D01*
X1665386Y339121D01*
X1666471Y339329D01*
X1667556Y338912D01*
X1668331Y337871D01*
G01X1675151Y332037D02*
X1676236Y333496D01*
X1677166Y334329D01*
X1678406Y334746D01*
X1679491Y334329D01*
X1680266Y333496D01*
X1680886Y332246D01*
X1681041Y330787D01*
X1680886Y329537D01*
X1680266Y328287D01*
X1679336Y327246D01*
X1678251Y326829D01*
X1677011Y327246D01*
X1675926Y328495D01*
X1675306Y330371D01*
X1675151Y332454D01*
X1675461Y335162D01*
X1675926Y336621D01*
X1676701Y338079D01*
X1677786Y339121D01*
X1678871Y339329D01*
X1679956Y338912D01*
X1680731Y337871D01*
G01X1668951Y309146D02*
X1669881Y310395D01*
X1670966Y311021D01*
X1672206Y311229D01*
X1673756Y310812D01*
X1674841Y309771D01*
X1675151Y308521D01*
X1674996Y307270D01*
X1674376Y306229D01*
X1671276Y304146D01*
X1669881Y302687D01*
X1668951Y300604D01*
X1668641Y298729D01*
X1675151D01*
G01X1665696Y270629D02*
Y283129D01*
X1663836Y280629D01*
G01Y270629D02*
X1667556D01*
G01X1678096D02*
Y283129D01*
X1676236Y280629D01*
G01Y270629D02*
X1679956D01*
G01X1649886Y413004D02*
X1650816Y411962D01*
X1651901Y411337D01*
X1653296Y411129D01*
X1654691Y411546D01*
X1655776Y412379D01*
X1656551Y413837D01*
X1656706Y415504D01*
X1656396Y417171D01*
X1655621Y418212D01*
X1654536Y419046D01*
X1653451Y419254D01*
X1652366Y419046D01*
X1650971Y418212D01*
X1651436Y423629D01*
X1655621D01*
G01X1665696Y411129D02*
X1666781Y411337D01*
X1668021Y411962D01*
X1668796Y413004D01*
X1669106Y414462D01*
X1668796Y415920D01*
X1667866Y417171D01*
X1666471Y417796D01*
X1664921D01*
X1663991Y418212D01*
X1663216Y419254D01*
X1662906Y420712D01*
X1663371Y422171D01*
X1664456Y423212D01*
X1665696Y423629D01*
X1666936Y423212D01*
X1668021Y422171D01*
X1668486Y420712D01*
X1668176Y419254D01*
X1667401Y418212D01*
X1666471Y417796D01*
X1664921D01*
X1663526Y417171D01*
X1662596Y415920D01*
X1662286Y414462D01*
X1662596Y413004D01*
X1663371Y411962D01*
X1664611Y411337D01*
X1665696Y411129D01*
G01X1678096Y423629D02*
X1676856Y423212D01*
X1675926Y422171D01*
X1675306Y420921D01*
X1674841Y419254D01*
X1674686Y417379D01*
X1674841Y415504D01*
X1675306Y413837D01*
X1675926Y412587D01*
X1676856Y411546D01*
X1678096Y411129D01*
X1679336Y411546D01*
X1680266Y412587D01*
X1680886Y413837D01*
X1681351Y415504D01*
X1681506Y417379D01*
X1681351Y419254D01*
X1680886Y420921D01*
X1680266Y422171D01*
X1679336Y423212D01*
X1678096Y423629D01*
G01X1692356Y411129D02*
Y423629D01*
X1686621Y414671D01*
X1694371D01*
G01X1662286Y384904D02*
X1663216Y383862D01*
X1664301Y383237D01*
X1665696Y383029D01*
X1667091Y383446D01*
X1668176Y384279D01*
X1668951Y385737D01*
X1669106Y387404D01*
X1668796Y389071D01*
X1668021Y390112D01*
X1666936Y390946D01*
X1665851Y391154D01*
X1664766Y390946D01*
X1663371Y390112D01*
X1663836Y395529D01*
X1668021D01*
G01X1675461Y384487D02*
X1676546Y383446D01*
X1677786Y383029D01*
X1679026Y383446D01*
X1680111Y384695D01*
X1680886Y386571D01*
X1681196Y388446D01*
Y390737D01*
X1680886Y392612D01*
X1680111Y394279D01*
X1679181Y395112D01*
X1678096Y395529D01*
X1676856Y395112D01*
X1675926Y394279D01*
X1675306Y393029D01*
X1674996Y391362D01*
X1675306Y389904D01*
X1676081Y388446D01*
X1677011Y387612D01*
X1678096Y387404D01*
X1679336Y387820D01*
X1680266Y388862D01*
X1681196Y390737D01*
G01X1659496Y354929D02*
Y367429D01*
X1657636Y364929D01*
G01Y354929D02*
X1661356D01*
G01X1668486Y357429D02*
X1669416Y355970D01*
X1670656Y355137D01*
X1672051Y354929D01*
X1673291Y355137D01*
X1674531Y356179D01*
X1675306Y357429D01*
X1675461Y358679D01*
X1675151Y360137D01*
X1674066Y361179D01*
X1672981Y361596D01*
X1671586D01*
G01X1672981D02*
X1673911Y362221D01*
X1674686Y363262D01*
X1674996Y364512D01*
X1674686Y365762D01*
X1673911Y366804D01*
X1672516Y367429D01*
X1671121Y367221D01*
X1669726Y366387D01*
G01X1680886Y356804D02*
X1681816Y355762D01*
X1682901Y355137D01*
X1684296Y354929D01*
X1685691Y355346D01*
X1686776Y356179D01*
X1687551Y357637D01*
X1687706Y359304D01*
X1687396Y360971D01*
X1686621Y362012D01*
X1685536Y362846D01*
X1684451Y363054D01*
X1683366Y362846D01*
X1681971Y362012D01*
X1682436Y367429D01*
X1686621D01*
G01X1659496Y440779D02*
X1658256Y440987D01*
X1657171Y441820D01*
X1656241Y443071D01*
X1655621Y444529D01*
X1655311Y446196D01*
Y447862D01*
X1655621Y449529D01*
X1656241Y450987D01*
X1657171Y452237D01*
X1658256Y453071D01*
X1659496Y453279D01*
X1660736Y453071D01*
X1661821Y452237D01*
X1662751Y450987D01*
X1663371Y449529D01*
X1663681Y447862D01*
Y446196D01*
X1663371Y444529D01*
X1662751Y443071D01*
X1661821Y441820D01*
X1660736Y440987D01*
X1659496Y440779D01*
G01X1660736Y444112D02*
X1662596Y440779D01*
G01X1671896Y453279D02*
Y440779D01*
G01X1668331Y453279D02*
X1675461D01*
G01X1684296Y440779D02*
Y446404D01*
X1681196Y453279D01*
G01X1687396D02*
X1684296Y446404D01*
G01X-7874Y0D02*
X-75552D01*
G02X-90552Y15000I0J15000D01*
G01Y519024D01*
G02X-75552Y534024I15000J0D01*
G01X-7874D01*
G01Y1030087D02*
X-75552D01*
G03X-90552Y1015087I0J-15000D01*
G01Y1001780D01*
G03X-75552Y986780I15000J0D01*
G01X-7874D01*
G01Y1992126D02*
X-75552D01*
G03X-90552Y1977126I0J-15000D01*
G01Y1915165D01*
G03X-75552Y1900165I15000J0D01*
G01X-7874D01*
G01X1023228Y1618051D02*
Y1675945D01*
G02X1028701Y1681417I5472J0D01*
G01X1033465D01*
X1037402Y1685354D01*
Y1988189D01*
G03X1033465Y1992126I-3937J0D01*
G01X3937D01*
G03X0Y1988189I0J-3937D01*
G01Y1661189D01*
X1969Y1659220D01*
X17323D01*
G02Y1650559I0J-4331D01*
G01X1969D01*
X0Y1648591D01*
Y1243866D01*
X1969Y1241898D01*
X17323D01*
G02Y1233236I0J-4331D01*
G01X1969D01*
X0Y1231268D01*
Y747803D01*
X1969Y745835D01*
X17323D01*
G02Y737173I0J-4331D01*
G01X1969D01*
X0Y735205D01*
Y3937D01*
G03X3937Y0I3937J0D01*
G01X121260D01*
X127310Y11888D01*
G03X127953Y14567I-5263J2680D01*
G01Y17717D01*
G02X139764I5906J0D01*
G01Y14567D01*
G03X140406Y11888I5906J-1D01*
G01X146457Y0D01*
X1033465D01*
G03X1037402Y3937I0J3937D01*
G01Y1424882D01*
X1033465Y1428819D01*
X1028701D01*
G02X1023228Y1434291I0J5473D01*
G01Y1609902D01*
X1021260Y1611870D01*
X993681D01*
G02Y1616083I0J2107D01*
G01X1021260D01*
X1023228Y1618051D01*
G01X-7874Y39059D02*
G03X0I3937J0D01*
G01Y8350D02*
G03X-7874I-3937J0D01*
G01D02*
Y0D01*
G01Y251657D02*
Y39059D01*
G01X0Y251657D02*
G03X-7874I-3937J0D01*
G01Y282366D02*
G03X0I3937J0D01*
G01X-7874Y494965D02*
Y282366D01*
G01X17323Y737174D02*
X1969D01*
X0Y735205D01*
Y548652D01*
G01X-7874Y525673D02*
G03X0I3937J0D01*
G01Y494965D02*
G03X-7874I-3937J0D01*
G01Y534024D02*
Y525673D01*
G01X17323Y745835D02*
X1969D01*
X0Y747804D01*
Y972152D01*
G01X17323Y745835D02*
G02Y737173I0J-4331D01*
G01X-12722Y801002D02*
X-12389Y801535D01*
X-12189Y802135D01*
Y802669D01*
X-12389Y803202D01*
X-12722Y803602D01*
X-13189Y803802D01*
X-13656Y803669D01*
X-14056Y803335D01*
X-14322Y802735D01*
X-14456Y801935D01*
X-14722Y801469D01*
X-15189Y801269D01*
X-15656Y801402D01*
X-15989Y801735D01*
X-16189Y802202D01*
Y802669D01*
X-16056Y803135D01*
X-15722Y803535D01*
G01X-12189Y807002D02*
X-16189D01*
G01X-14856Y811602D02*
X-12189D01*
G01X-15922D02*
X-15989Y811469D01*
X-16122D01*
X-16189Y811602D01*
X-16122Y811735D01*
X-15989D01*
X-15922Y811602D01*
G01X-16189Y816202D02*
X-12189D01*
G01X-14856Y815269D02*
Y817135D01*
G01X-615Y809932D02*
X-2615Y811932D01*
Y807932D01*
X-615Y809932D01*
X-8615D01*
G01X0Y993079D02*
G03X-7874I-3937J0D01*
G01Y986780D02*
Y993079D01*
G01X17323Y1233237D02*
X1969D01*
X0Y1231268D01*
Y1044715D01*
G01X-7874Y1023787D02*
G03X0I3937J0D01*
G01X-7874D02*
Y1030087D01*
G01X17323Y1241898D02*
X1969D01*
X0Y1243867D01*
Y1468215D01*
G01X17323Y1241898D02*
G02Y1233236I0J-4331D01*
G01X-12722Y1297065D02*
X-12389Y1297598D01*
X-12189Y1298198D01*
Y1298732D01*
X-12389Y1299265D01*
X-12722Y1299665D01*
X-13189Y1299865D01*
X-13656Y1299732D01*
X-14056Y1299398D01*
X-14322Y1298798D01*
X-14456Y1297998D01*
X-14722Y1297532D01*
X-15189Y1297332D01*
X-15656Y1297465D01*
X-15989Y1297798D01*
X-16189Y1298265D01*
Y1298732D01*
X-16056Y1299198D01*
X-15722Y1299598D01*
G01X-12189Y1303065D02*
X-16189D01*
G01X-14856Y1307665D02*
X-12189D01*
G01X-15922D02*
X-15989Y1307532D01*
X-16122D01*
X-16189Y1307665D01*
X-16122Y1307798D01*
X-15989D01*
X-15922Y1307665D01*
G01X-16189Y1312265D02*
X-12189D01*
G01X-14856Y1311332D02*
Y1313198D01*
G01X-615Y1305995D02*
X-2615Y1307995D01*
Y1303995D01*
X-615Y1305995D01*
X-8615D01*
G01X17323Y1650559D02*
X1969D01*
X0Y1648590D01*
Y1462037D01*
G01X-12722Y1714387D02*
X-12389Y1714920D01*
X-12189Y1715520D01*
Y1716054D01*
X-12389Y1716587D01*
X-12722Y1716987D01*
X-13189Y1717187D01*
X-13656Y1717054D01*
X-14056Y1716720D01*
X-14322Y1716120D01*
X-14456Y1715320D01*
X-14722Y1714854D01*
X-15189Y1714654D01*
X-15656Y1714787D01*
X-15989Y1715120D01*
X-16189Y1715587D01*
Y1716054D01*
X-16056Y1716520D01*
X-15722Y1716920D01*
G01X-12189Y1720387D02*
X-16189D01*
G01X-14856Y1724987D02*
X-12189D01*
G01X-15922D02*
X-15989Y1724854D01*
X-16122D01*
X-16189Y1724987D01*
X-16122Y1725120D01*
X-15989D01*
X-15922Y1724987D01*
G01X-16189Y1729587D02*
X-12189D01*
G01X-14856Y1728654D02*
Y1730520D01*
G01X17323Y1659220D02*
X1969D01*
X0Y1661189D01*
Y1885537D01*
G01X17323Y1659220D02*
G02Y1650558I0J-4331D01*
G01X-615Y1723317D02*
X-2615Y1725317D01*
Y1721317D01*
X-615Y1723317D01*
X-8615D01*
G01X-7874Y1930791D02*
Y1900165D01*
G01X0Y1930791D02*
G03X-7874I-3937J0D01*
G01X33054Y1906385D02*
Y1910385D01*
X32254Y1909585D01*
G01Y1906385D02*
X33854D01*
G01X36521Y1906852D02*
X36987Y1906518D01*
X37521Y1906385D01*
X38054Y1906518D01*
X38521Y1906918D01*
X38854Y1907518D01*
X38987Y1908118D01*
Y1908852D01*
X38854Y1909452D01*
X38521Y1909985D01*
X38121Y1910252D01*
X37654Y1910385D01*
X37121Y1910252D01*
X36721Y1909985D01*
X36454Y1909585D01*
X36321Y1909052D01*
X36454Y1908585D01*
X36787Y1908118D01*
X37187Y1907852D01*
X37654Y1907785D01*
X38187Y1907918D01*
X38587Y1908252D01*
X38987Y1908852D01*
G01X42121Y1906385D02*
X42254Y1907252D01*
X42454Y1907985D01*
X42721Y1908652D01*
X43054Y1909385D01*
X43587Y1910385D01*
X40921D01*
G01X45454Y1906385D02*
X48254Y1910385D01*
G01X45454D02*
X48254Y1906385D01*
G01X50187Y1909718D02*
X50587Y1910118D01*
X51054Y1910318D01*
X51587Y1910385D01*
X52254Y1910252D01*
X52721Y1909918D01*
X52854Y1909518D01*
X52787Y1909118D01*
X52521Y1908785D01*
X51187Y1908118D01*
X50587Y1907652D01*
X50187Y1906985D01*
X50054Y1906385D01*
X52854D01*
G01X54921Y1906852D02*
X55387Y1906518D01*
X55921Y1906385D01*
X56454Y1906518D01*
X56921Y1906918D01*
X57254Y1907518D01*
X57387Y1908118D01*
Y1908852D01*
X57254Y1909452D01*
X56921Y1909985D01*
X56521Y1910252D01*
X56054Y1910385D01*
X55521Y1910252D01*
X55121Y1909985D01*
X54854Y1909585D01*
X54721Y1909052D01*
X54854Y1908585D01*
X55187Y1908118D01*
X55587Y1907852D01*
X56054Y1907785D01*
X56587Y1907918D01*
X56987Y1908252D01*
X57387Y1908852D01*
G01X59387Y1908052D02*
X59854Y1908518D01*
X60254Y1908785D01*
X60787Y1908918D01*
X61254Y1908785D01*
X61587Y1908518D01*
X61854Y1908118D01*
X61921Y1907652D01*
X61854Y1907252D01*
X61587Y1906852D01*
X61187Y1906518D01*
X60721Y1906385D01*
X60187Y1906518D01*
X59721Y1906918D01*
X59454Y1907518D01*
X59387Y1908185D01*
X59521Y1909052D01*
X59721Y1909518D01*
X60054Y1909985D01*
X60521Y1910318D01*
X60987Y1910385D01*
X61454Y1910252D01*
X61787Y1909918D01*
G01X-7874Y1961500D02*
G03X0I3937J0D01*
G01X-7874Y1992126D02*
Y1961500D01*
G01X62287Y28794D02*
X62754Y29194D01*
X63020Y29728D01*
X63087Y30328D01*
X63020Y30861D01*
X62687Y31394D01*
X62287Y31728D01*
X61887Y31794D01*
X61420Y31661D01*
X61087Y31194D01*
X60954Y30728D01*
Y30128D01*
G01Y30728D02*
X60754Y31128D01*
X60420Y31461D01*
X60020Y31594D01*
X59620Y31461D01*
X59287Y31128D01*
X59087Y30528D01*
X59154Y29928D01*
X59420Y29328D01*
G01X59754Y33594D02*
X59354Y33994D01*
X59154Y34461D01*
X59087Y34994D01*
X59220Y35661D01*
X59554Y36128D01*
X59954Y36261D01*
X60354Y36194D01*
X60687Y35928D01*
X61354Y34594D01*
X61820Y33994D01*
X62487Y33594D01*
X63087Y33461D01*
Y36261D01*
G01Y38061D02*
X59087Y40861D01*
G01Y38061D02*
X63087Y40861D01*
G01Y43928D02*
X62220Y44061D01*
X61487Y44261D01*
X60820Y44528D01*
X60087Y44861D01*
X59087Y45394D01*
Y42728D01*
G01X62487Y47194D02*
X62820Y47594D01*
X63020Y48061D01*
X63087Y48661D01*
X62954Y49261D01*
X62687Y49728D01*
X62220Y50061D01*
X61687Y50128D01*
X61154Y49994D01*
X60820Y49661D01*
X60554Y49194D01*
X60487Y48728D01*
X60554Y48261D01*
X60820Y47661D01*
X59087Y47861D01*
Y49661D01*
G01X63287Y156794D02*
X63754Y157194D01*
X64020Y157728D01*
X64087Y158328D01*
X64020Y158861D01*
X63687Y159394D01*
X63287Y159728D01*
X62887Y159794D01*
X62420Y159661D01*
X62087Y159194D01*
X61954Y158728D01*
Y158128D01*
G01Y158728D02*
X61754Y159128D01*
X61420Y159461D01*
X61020Y159594D01*
X60620Y159461D01*
X60287Y159128D01*
X60087Y158528D01*
X60154Y157928D01*
X60420Y157328D01*
G01X60754Y161594D02*
X60354Y161994D01*
X60154Y162461D01*
X60087Y162994D01*
X60220Y163661D01*
X60554Y164128D01*
X60954Y164261D01*
X61354Y164194D01*
X61687Y163928D01*
X62354Y162594D01*
X62820Y161994D01*
X63487Y161594D01*
X64087Y161461D01*
Y164261D01*
G01Y166061D02*
X60087Y168861D01*
G01Y166061D02*
X64087Y168861D01*
G01Y171928D02*
X63220Y172061D01*
X62487Y172261D01*
X61820Y172528D01*
X61087Y172861D01*
X60087Y173394D01*
Y170728D01*
G01X63487Y175194D02*
X63820Y175594D01*
X64020Y176061D01*
X64087Y176661D01*
X63954Y177261D01*
X63687Y177728D01*
X63220Y178061D01*
X62687Y178128D01*
X62154Y177994D01*
X61820Y177661D01*
X61554Y177194D01*
X61487Y176728D01*
X61554Y176261D01*
X61820Y175661D01*
X60087Y175861D01*
Y177661D01*
G01X44865Y265046D02*
Y269046D01*
X44065Y268246D01*
G01Y265046D02*
X45665D01*
G01X48332Y265513D02*
X48798Y265179D01*
X49332Y265046D01*
X49865Y265179D01*
X50332Y265579D01*
X50665Y266179D01*
X50798Y266779D01*
Y267513D01*
X50665Y268113D01*
X50332Y268646D01*
X49932Y268913D01*
X49465Y269046D01*
X48932Y268913D01*
X48532Y268646D01*
X48265Y268246D01*
X48132Y267713D01*
X48265Y267246D01*
X48598Y266779D01*
X48998Y266513D01*
X49465Y266446D01*
X49998Y266579D01*
X50398Y266913D01*
X50798Y267513D01*
G01X53932Y265046D02*
X54065Y265913D01*
X54265Y266646D01*
X54532Y267313D01*
X54865Y268046D01*
X55398Y269046D01*
X52732D01*
G01X57265Y265046D02*
X60065Y269046D01*
G01X57265D02*
X60065Y265046D01*
G01X61998Y268379D02*
X62398Y268779D01*
X62865Y268979D01*
X63398Y269046D01*
X64065Y268913D01*
X64532Y268579D01*
X64665Y268179D01*
X64598Y267779D01*
X64332Y267446D01*
X62998Y266779D01*
X62398Y266313D01*
X61998Y265646D01*
X61865Y265046D01*
X64665D01*
G01X66732Y265513D02*
X67198Y265179D01*
X67732Y265046D01*
X68265Y265179D01*
X68732Y265579D01*
X69065Y266179D01*
X69198Y266779D01*
Y267513D01*
X69065Y268113D01*
X68732Y268646D01*
X68332Y268913D01*
X67865Y269046D01*
X67332Y268913D01*
X66932Y268646D01*
X66665Y268246D01*
X66532Y267713D01*
X66665Y267246D01*
X66998Y266779D01*
X67398Y266513D01*
X67865Y266446D01*
X68398Y266579D01*
X68798Y266913D01*
X69198Y267513D01*
G01X71198Y266713D02*
X71665Y267179D01*
X72065Y267446D01*
X72598Y267579D01*
X73065Y267446D01*
X73398Y267179D01*
X73665Y266779D01*
X73732Y266313D01*
X73665Y265913D01*
X73398Y265513D01*
X72998Y265179D01*
X72532Y265046D01*
X71998Y265179D01*
X71532Y265579D01*
X71265Y266179D01*
X71198Y266846D01*
X71332Y267713D01*
X71532Y268179D01*
X71865Y268646D01*
X72332Y268979D01*
X72798Y269046D01*
X73265Y268913D01*
X73598Y268579D01*
G01X62287Y434306D02*
X62754Y434706D01*
X63020Y435240D01*
X63087Y435840D01*
X63020Y436373D01*
X62687Y436906D01*
X62287Y437240D01*
X61887Y437306D01*
X61420Y437173D01*
X61087Y436706D01*
X60954Y436240D01*
Y435640D01*
G01Y436240D02*
X60754Y436640D01*
X60420Y436973D01*
X60020Y437106D01*
X59620Y436973D01*
X59287Y436640D01*
X59087Y436040D01*
X59154Y435440D01*
X59420Y434840D01*
G01X59754Y439106D02*
X59354Y439506D01*
X59154Y439973D01*
X59087Y440506D01*
X59220Y441173D01*
X59554Y441640D01*
X59954Y441773D01*
X60354Y441706D01*
X60687Y441440D01*
X61354Y440106D01*
X61820Y439506D01*
X62487Y439106D01*
X63087Y438973D01*
Y441773D01*
G01Y443573D02*
X59087Y446373D01*
G01Y443573D02*
X63087Y446373D01*
G01Y449440D02*
X62220Y449573D01*
X61487Y449773D01*
X60820Y450040D01*
X60087Y450373D01*
X59087Y450906D01*
Y448240D01*
G01X62487Y452706D02*
X62820Y453106D01*
X63020Y453573D01*
X63087Y454173D01*
X62954Y454773D01*
X62687Y455240D01*
X62220Y455573D01*
X61687Y455640D01*
X61154Y455506D01*
X60820Y455173D01*
X60554Y454706D01*
X60487Y454240D01*
X60554Y453773D01*
X60820Y453173D01*
X59087Y453373D01*
Y455173D01*
G01X63287Y562306D02*
X63754Y562706D01*
X64020Y563240D01*
X64087Y563840D01*
X64020Y564373D01*
X63687Y564906D01*
X63287Y565240D01*
X62887Y565306D01*
X62420Y565173D01*
X62087Y564706D01*
X61954Y564240D01*
Y563640D01*
G01Y564240D02*
X61754Y564640D01*
X61420Y564973D01*
X61020Y565106D01*
X60620Y564973D01*
X60287Y564640D01*
X60087Y564040D01*
X60154Y563440D01*
X60420Y562840D01*
G01X60754Y567106D02*
X60354Y567506D01*
X60154Y567973D01*
X60087Y568506D01*
X60220Y569173D01*
X60554Y569640D01*
X60954Y569773D01*
X61354Y569706D01*
X61687Y569440D01*
X62354Y568106D01*
X62820Y567506D01*
X63487Y567106D01*
X64087Y566973D01*
Y569773D01*
G01Y571573D02*
X60087Y574373D01*
G01Y571573D02*
X64087Y574373D01*
G01Y577440D02*
X63220Y577573D01*
X62487Y577773D01*
X61820Y578040D01*
X61087Y578373D01*
X60087Y578906D01*
Y576240D01*
G01X63487Y580706D02*
X63820Y581106D01*
X64020Y581573D01*
X64087Y582173D01*
X63954Y582773D01*
X63687Y583240D01*
X63220Y583573D01*
X62687Y583640D01*
X62154Y583506D01*
X61820Y583173D01*
X61554Y582706D01*
X61487Y582240D01*
X61554Y581773D01*
X61820Y581173D01*
X60087Y581373D01*
Y583173D01*
G01X62287Y839818D02*
X62754Y840218D01*
X63020Y840752D01*
X63087Y841352D01*
X63020Y841885D01*
X62687Y842418D01*
X62287Y842752D01*
X61887Y842818D01*
X61420Y842685D01*
X61087Y842218D01*
X60954Y841752D01*
Y841152D01*
G01Y841752D02*
X60754Y842152D01*
X60420Y842485D01*
X60020Y842618D01*
X59620Y842485D01*
X59287Y842152D01*
X59087Y841552D01*
X59154Y840952D01*
X59420Y840352D01*
G01X59754Y844618D02*
X59354Y845018D01*
X59154Y845485D01*
X59087Y846018D01*
X59220Y846685D01*
X59554Y847152D01*
X59954Y847285D01*
X60354Y847218D01*
X60687Y846952D01*
X61354Y845618D01*
X61820Y845018D01*
X62487Y844618D01*
X63087Y844485D01*
Y847285D01*
G01Y849085D02*
X59087Y851885D01*
G01Y849085D02*
X63087Y851885D01*
G01Y854952D02*
X62220Y855085D01*
X61487Y855285D01*
X60820Y855552D01*
X60087Y855885D01*
X59087Y856418D01*
Y853752D01*
G01X62487Y858218D02*
X62820Y858618D01*
X63020Y859085D01*
X63087Y859685D01*
X62954Y860285D01*
X62687Y860752D01*
X62220Y861085D01*
X61687Y861152D01*
X61154Y861018D01*
X60820Y860685D01*
X60554Y860218D01*
X60487Y859752D01*
X60554Y859285D01*
X60820Y858685D01*
X59087Y858885D01*
Y860685D01*
G01X63287Y967818D02*
X63754Y968218D01*
X64020Y968752D01*
X64087Y969352D01*
X64020Y969885D01*
X63687Y970418D01*
X63287Y970752D01*
X62887Y970818D01*
X62420Y970685D01*
X62087Y970218D01*
X61954Y969752D01*
Y969152D01*
G01Y969752D02*
X61754Y970152D01*
X61420Y970485D01*
X61020Y970618D01*
X60620Y970485D01*
X60287Y970152D01*
X60087Y969552D01*
X60154Y968952D01*
X60420Y968352D01*
G01X60754Y972618D02*
X60354Y973018D01*
X60154Y973485D01*
X60087Y974018D01*
X60220Y974685D01*
X60554Y975152D01*
X60954Y975285D01*
X61354Y975218D01*
X61687Y974952D01*
X62354Y973618D01*
X62820Y973018D01*
X63487Y972618D01*
X64087Y972485D01*
Y975285D01*
G01Y977085D02*
X60087Y979885D01*
G01Y977085D02*
X64087Y979885D01*
G01Y982952D02*
X63220Y983085D01*
X62487Y983285D01*
X61820Y983552D01*
X61087Y983885D01*
X60087Y984418D01*
Y981752D01*
G01X63487Y986218D02*
X63820Y986618D01*
X64020Y987085D01*
X64087Y987685D01*
X63954Y988285D01*
X63687Y988752D01*
X63220Y989085D01*
X62687Y989152D01*
X62154Y989018D01*
X61820Y988685D01*
X61554Y988218D01*
X61487Y987752D01*
X61554Y987285D01*
X61820Y986685D01*
X60087Y986885D01*
Y988685D01*
G01X62287Y1245330D02*
X62754Y1245730D01*
X63020Y1246264D01*
X63087Y1246864D01*
X63020Y1247397D01*
X62687Y1247930D01*
X62287Y1248264D01*
X61887Y1248330D01*
X61420Y1248197D01*
X61087Y1247730D01*
X60954Y1247264D01*
Y1246664D01*
G01Y1247264D02*
X60754Y1247664D01*
X60420Y1247997D01*
X60020Y1248130D01*
X59620Y1247997D01*
X59287Y1247664D01*
X59087Y1247064D01*
X59154Y1246464D01*
X59420Y1245864D01*
G01X59754Y1250130D02*
X59354Y1250530D01*
X59154Y1250997D01*
X59087Y1251530D01*
X59220Y1252197D01*
X59554Y1252664D01*
X59954Y1252797D01*
X60354Y1252730D01*
X60687Y1252464D01*
X61354Y1251130D01*
X61820Y1250530D01*
X62487Y1250130D01*
X63087Y1249997D01*
Y1252797D01*
G01Y1254597D02*
X59087Y1257397D01*
G01Y1254597D02*
X63087Y1257397D01*
G01Y1260464D02*
X62220Y1260597D01*
X61487Y1260797D01*
X60820Y1261064D01*
X60087Y1261397D01*
X59087Y1261930D01*
Y1259264D01*
G01X62487Y1263730D02*
X62820Y1264130D01*
X63020Y1264597D01*
X63087Y1265197D01*
X62954Y1265797D01*
X62687Y1266264D01*
X62220Y1266597D01*
X61687Y1266664D01*
X61154Y1266530D01*
X60820Y1266197D01*
X60554Y1265730D01*
X60487Y1265264D01*
X60554Y1264797D01*
X60820Y1264197D01*
X59087Y1264397D01*
Y1266197D01*
G01X63287Y1373330D02*
X63754Y1373730D01*
X64020Y1374264D01*
X64087Y1374864D01*
X64020Y1375397D01*
X63687Y1375930D01*
X63287Y1376264D01*
X62887Y1376330D01*
X62420Y1376197D01*
X62087Y1375730D01*
X61954Y1375264D01*
Y1374664D01*
G01Y1375264D02*
X61754Y1375664D01*
X61420Y1375997D01*
X61020Y1376130D01*
X60620Y1375997D01*
X60287Y1375664D01*
X60087Y1375064D01*
X60154Y1374464D01*
X60420Y1373864D01*
G01X60754Y1378130D02*
X60354Y1378530D01*
X60154Y1378997D01*
X60087Y1379530D01*
X60220Y1380197D01*
X60554Y1380664D01*
X60954Y1380797D01*
X61354Y1380730D01*
X61687Y1380464D01*
X62354Y1379130D01*
X62820Y1378530D01*
X63487Y1378130D01*
X64087Y1377997D01*
Y1380797D01*
G01Y1382597D02*
X60087Y1385397D01*
G01Y1382597D02*
X64087Y1385397D01*
G01Y1388464D02*
X63220Y1388597D01*
X62487Y1388797D01*
X61820Y1389064D01*
X61087Y1389397D01*
X60087Y1389930D01*
Y1387264D01*
G01X63487Y1391730D02*
X63820Y1392130D01*
X64020Y1392597D01*
X64087Y1393197D01*
X63954Y1393797D01*
X63687Y1394264D01*
X63220Y1394597D01*
X62687Y1394664D01*
X62154Y1394530D01*
X61820Y1394197D01*
X61554Y1393730D01*
X61487Y1393264D01*
X61554Y1392797D01*
X61820Y1392197D01*
X60087Y1392397D01*
Y1394197D01*
G01X62287Y1650842D02*
X62754Y1651242D01*
X63020Y1651776D01*
X63087Y1652376D01*
X63020Y1652909D01*
X62687Y1653442D01*
X62287Y1653776D01*
X61887Y1653842D01*
X61420Y1653709D01*
X61087Y1653242D01*
X60954Y1652776D01*
Y1652176D01*
G01Y1652776D02*
X60754Y1653176D01*
X60420Y1653509D01*
X60020Y1653642D01*
X59620Y1653509D01*
X59287Y1653176D01*
X59087Y1652576D01*
X59154Y1651976D01*
X59420Y1651376D01*
G01X59754Y1655642D02*
X59354Y1656042D01*
X59154Y1656509D01*
X59087Y1657042D01*
X59220Y1657709D01*
X59554Y1658176D01*
X59954Y1658309D01*
X60354Y1658242D01*
X60687Y1657976D01*
X61354Y1656642D01*
X61820Y1656042D01*
X62487Y1655642D01*
X63087Y1655509D01*
Y1658309D01*
G01Y1660109D02*
X59087Y1662909D01*
G01Y1660109D02*
X63087Y1662909D01*
G01Y1665976D02*
X62220Y1666109D01*
X61487Y1666309D01*
X60820Y1666576D01*
X60087Y1666909D01*
X59087Y1667442D01*
Y1664776D01*
G01X62487Y1669242D02*
X62820Y1669642D01*
X63020Y1670109D01*
X63087Y1670709D01*
X62954Y1671309D01*
X62687Y1671776D01*
X62220Y1672109D01*
X61687Y1672176D01*
X61154Y1672042D01*
X60820Y1671709D01*
X60554Y1671242D01*
X60487Y1670776D01*
X60554Y1670309D01*
X60820Y1669709D01*
X59087Y1669909D01*
Y1671709D01*
G01X63287Y1778842D02*
X63754Y1779242D01*
X64020Y1779776D01*
X64087Y1780376D01*
X64020Y1780909D01*
X63687Y1781442D01*
X63287Y1781776D01*
X62887Y1781842D01*
X62420Y1781709D01*
X62087Y1781242D01*
X61954Y1780776D01*
Y1780176D01*
G01Y1780776D02*
X61754Y1781176D01*
X61420Y1781509D01*
X61020Y1781642D01*
X60620Y1781509D01*
X60287Y1781176D01*
X60087Y1780576D01*
X60154Y1779976D01*
X60420Y1779376D01*
G01X60754Y1783642D02*
X60354Y1784042D01*
X60154Y1784509D01*
X60087Y1785042D01*
X60220Y1785709D01*
X60554Y1786176D01*
X60954Y1786309D01*
X61354Y1786242D01*
X61687Y1785976D01*
X62354Y1784642D01*
X62820Y1784042D01*
X63487Y1783642D01*
X64087Y1783509D01*
Y1786309D01*
G01Y1788109D02*
X60087Y1790909D01*
G01Y1788109D02*
X64087Y1790909D01*
G01Y1793976D02*
X63220Y1794109D01*
X62487Y1794309D01*
X61820Y1794576D01*
X61087Y1794909D01*
X60087Y1795442D01*
Y1792776D01*
G01X63487Y1797242D02*
X63820Y1797642D01*
X64020Y1798109D01*
X64087Y1798709D01*
X63954Y1799309D01*
X63687Y1799776D01*
X63220Y1800109D01*
X62687Y1800176D01*
X62154Y1800042D01*
X61820Y1799709D01*
X61554Y1799242D01*
X61487Y1798776D01*
X61554Y1798309D01*
X61820Y1797709D01*
X60087Y1797909D01*
Y1799709D01*
G01X145258Y1267D02*
Y5267D01*
X144458Y4467D01*
G01Y1267D02*
X146058D01*
G01X148725Y1734D02*
X149191Y1400D01*
X149725Y1267D01*
X150258Y1400D01*
X150725Y1800D01*
X151058Y2400D01*
X151191Y3000D01*
Y3734D01*
X151058Y4334D01*
X150725Y4867D01*
X150325Y5134D01*
X149858Y5267D01*
X149325Y5134D01*
X148925Y4867D01*
X148658Y4467D01*
X148525Y3934D01*
X148658Y3467D01*
X148991Y3000D01*
X149391Y2734D01*
X149858Y2667D01*
X150391Y2800D01*
X150791Y3134D01*
X151191Y3734D01*
G01X154325Y1267D02*
X154458Y2134D01*
X154658Y2867D01*
X154925Y3534D01*
X155258Y4267D01*
X155791Y5267D01*
X153125D01*
G01X157658Y1267D02*
X160458Y5267D01*
G01X157658D02*
X160458Y1267D01*
G01X162391Y4600D02*
X162791Y5000D01*
X163258Y5200D01*
X163791Y5267D01*
X164458Y5134D01*
X164925Y4800D01*
X165058Y4400D01*
X164991Y4000D01*
X164725Y3667D01*
X163391Y3000D01*
X162791Y2534D01*
X162391Y1867D01*
X162258Y1267D01*
X165058D01*
G01X167125Y1734D02*
X167591Y1400D01*
X168125Y1267D01*
X168658Y1400D01*
X169125Y1800D01*
X169458Y2400D01*
X169591Y3000D01*
Y3734D01*
X169458Y4334D01*
X169125Y4867D01*
X168725Y5134D01*
X168258Y5267D01*
X167725Y5134D01*
X167325Y4867D01*
X167058Y4467D01*
X166925Y3934D01*
X167058Y3467D01*
X167391Y3000D01*
X167791Y2734D01*
X168258Y2667D01*
X168791Y2800D01*
X169191Y3134D01*
X169591Y3734D01*
G01X171591Y2934D02*
X172058Y3400D01*
X172458Y3667D01*
X172991Y3800D01*
X173458Y3667D01*
X173791Y3400D01*
X174058Y3000D01*
X174125Y2534D01*
X174058Y2134D01*
X173791Y1734D01*
X173391Y1400D01*
X172925Y1267D01*
X172391Y1400D01*
X171925Y1800D01*
X171658Y2400D01*
X171591Y3067D01*
X171725Y3934D01*
X171925Y4400D01*
X172258Y4867D01*
X172725Y5200D01*
X173191Y5267D01*
X173658Y5134D01*
X173991Y4800D01*
G01X183208Y191950D02*
X183675Y192350D01*
X183941Y192884D01*
X184008Y193484D01*
X183941Y194017D01*
X183608Y194550D01*
X183208Y194884D01*
X182808Y194950D01*
X182341Y194817D01*
X182008Y194350D01*
X181875Y193884D01*
Y193284D01*
G01Y193884D02*
X181675Y194284D01*
X181341Y194617D01*
X180941Y194750D01*
X180541Y194617D01*
X180208Y194284D01*
X180008Y193684D01*
X180075Y193084D01*
X180341Y192484D01*
G01X180675Y196750D02*
X180275Y197150D01*
X180075Y197617D01*
X180008Y198150D01*
X180141Y198817D01*
X180475Y199284D01*
X180875Y199417D01*
X181275Y199350D01*
X181608Y199084D01*
X182275Y197750D01*
X182741Y197150D01*
X183408Y196750D01*
X184008Y196617D01*
Y199417D01*
G01Y201217D02*
X180008Y204017D01*
G01Y201217D02*
X184008Y204017D01*
G01Y207084D02*
X183141Y207217D01*
X182408Y207417D01*
X181741Y207684D01*
X181008Y208017D01*
X180008Y208550D01*
Y205884D01*
G01X183408Y210350D02*
X183741Y210750D01*
X183941Y211217D01*
X184008Y211817D01*
X183875Y212417D01*
X183608Y212884D01*
X183141Y213217D01*
X182608Y213284D01*
X182075Y213150D01*
X181741Y212817D01*
X181475Y212350D01*
X181408Y211884D01*
X181475Y211417D01*
X181741Y210817D01*
X180008Y211017D01*
Y212817D01*
G01X184208Y319950D02*
X184675Y320350D01*
X184941Y320884D01*
X185008Y321484D01*
X184941Y322017D01*
X184608Y322550D01*
X184208Y322884D01*
X183808Y322950D01*
X183341Y322817D01*
X183008Y322350D01*
X182875Y321884D01*
Y321284D01*
G01Y321884D02*
X182675Y322284D01*
X182341Y322617D01*
X181941Y322750D01*
X181541Y322617D01*
X181208Y322284D01*
X181008Y321684D01*
X181075Y321084D01*
X181341Y320484D01*
G01X181675Y324750D02*
X181275Y325150D01*
X181075Y325617D01*
X181008Y326150D01*
X181141Y326817D01*
X181475Y327284D01*
X181875Y327417D01*
X182275Y327350D01*
X182608Y327084D01*
X183275Y325750D01*
X183741Y325150D01*
X184408Y324750D01*
X185008Y324617D01*
Y327417D01*
G01Y329217D02*
X181008Y332017D01*
G01Y329217D02*
X185008Y332017D01*
G01Y335084D02*
X184141Y335217D01*
X183408Y335417D01*
X182741Y335684D01*
X182008Y336017D01*
X181008Y336550D01*
Y333884D01*
G01X184408Y338350D02*
X184741Y338750D01*
X184941Y339217D01*
X185008Y339817D01*
X184875Y340417D01*
X184608Y340884D01*
X184141Y341217D01*
X183608Y341284D01*
X183075Y341150D01*
X182741Y340817D01*
X182475Y340350D01*
X182408Y339884D01*
X182475Y339417D01*
X182741Y338817D01*
X181008Y339017D01*
Y340817D01*
G01X183208Y597462D02*
X183675Y597862D01*
X183941Y598396D01*
X184008Y598996D01*
X183941Y599529D01*
X183608Y600062D01*
X183208Y600396D01*
X182808Y600462D01*
X182341Y600329D01*
X182008Y599862D01*
X181875Y599396D01*
Y598796D01*
G01Y599396D02*
X181675Y599796D01*
X181341Y600129D01*
X180941Y600262D01*
X180541Y600129D01*
X180208Y599796D01*
X180008Y599196D01*
X180075Y598596D01*
X180341Y597996D01*
G01X180675Y602262D02*
X180275Y602662D01*
X180075Y603129D01*
X180008Y603662D01*
X180141Y604329D01*
X180475Y604796D01*
X180875Y604929D01*
X181275Y604862D01*
X181608Y604596D01*
X182275Y603262D01*
X182741Y602662D01*
X183408Y602262D01*
X184008Y602129D01*
Y604929D01*
G01Y606729D02*
X180008Y609529D01*
G01Y606729D02*
X184008Y609529D01*
G01Y612596D02*
X183141Y612729D01*
X182408Y612929D01*
X181741Y613196D01*
X181008Y613529D01*
X180008Y614062D01*
Y611396D01*
G01X183408Y615862D02*
X183741Y616262D01*
X183941Y616729D01*
X184008Y617329D01*
X183875Y617929D01*
X183608Y618396D01*
X183141Y618729D01*
X182608Y618796D01*
X182075Y618662D01*
X181741Y618329D01*
X181475Y617862D01*
X181408Y617396D01*
X181475Y616929D01*
X181741Y616329D01*
X180008Y616529D01*
Y618329D01*
G01X184208Y725462D02*
X184675Y725862D01*
X184941Y726396D01*
X185008Y726996D01*
X184941Y727529D01*
X184608Y728062D01*
X184208Y728396D01*
X183808Y728462D01*
X183341Y728329D01*
X183008Y727862D01*
X182875Y727396D01*
Y726796D01*
G01Y727396D02*
X182675Y727796D01*
X182341Y728129D01*
X181941Y728262D01*
X181541Y728129D01*
X181208Y727796D01*
X181008Y727196D01*
X181075Y726596D01*
X181341Y725996D01*
G01X181675Y730262D02*
X181275Y730662D01*
X181075Y731129D01*
X181008Y731662D01*
X181141Y732329D01*
X181475Y732796D01*
X181875Y732929D01*
X182275Y732862D01*
X182608Y732596D01*
X183275Y731262D01*
X183741Y730662D01*
X184408Y730262D01*
X185008Y730129D01*
Y732929D01*
G01Y734729D02*
X181008Y737529D01*
G01Y734729D02*
X185008Y737529D01*
G01Y740596D02*
X184141Y740729D01*
X183408Y740929D01*
X182741Y741196D01*
X182008Y741529D01*
X181008Y742062D01*
Y739396D01*
G01X184408Y743862D02*
X184741Y744262D01*
X184941Y744729D01*
X185008Y745329D01*
X184875Y745929D01*
X184608Y746396D01*
X184141Y746729D01*
X183608Y746796D01*
X183075Y746662D01*
X182741Y746329D01*
X182475Y745862D01*
X182408Y745396D01*
X182475Y744929D01*
X182741Y744329D01*
X181008Y744529D01*
Y746329D01*
G01X183208Y1002974D02*
X183675Y1003374D01*
X183941Y1003908D01*
X184008Y1004508D01*
X183941Y1005041D01*
X183608Y1005574D01*
X183208Y1005908D01*
X182808Y1005974D01*
X182341Y1005841D01*
X182008Y1005374D01*
X181875Y1004908D01*
Y1004308D01*
G01Y1004908D02*
X181675Y1005308D01*
X181341Y1005641D01*
X180941Y1005774D01*
X180541Y1005641D01*
X180208Y1005308D01*
X180008Y1004708D01*
X180075Y1004108D01*
X180341Y1003508D01*
G01X180675Y1007774D02*
X180275Y1008174D01*
X180075Y1008641D01*
X180008Y1009174D01*
X180141Y1009841D01*
X180475Y1010308D01*
X180875Y1010441D01*
X181275Y1010374D01*
X181608Y1010108D01*
X182275Y1008774D01*
X182741Y1008174D01*
X183408Y1007774D01*
X184008Y1007641D01*
Y1010441D01*
G01Y1012241D02*
X180008Y1015041D01*
G01Y1012241D02*
X184008Y1015041D01*
G01Y1018108D02*
X183141Y1018241D01*
X182408Y1018441D01*
X181741Y1018708D01*
X181008Y1019041D01*
X180008Y1019574D01*
Y1016908D01*
G01X183408Y1021374D02*
X183741Y1021774D01*
X183941Y1022241D01*
X184008Y1022841D01*
X183875Y1023441D01*
X183608Y1023908D01*
X183141Y1024241D01*
X182608Y1024308D01*
X182075Y1024174D01*
X181741Y1023841D01*
X181475Y1023374D01*
X181408Y1022908D01*
X181475Y1022441D01*
X181741Y1021841D01*
X180008Y1022041D01*
Y1023841D01*
G01X184208Y1130974D02*
X184675Y1131374D01*
X184941Y1131908D01*
X185008Y1132508D01*
X184941Y1133041D01*
X184608Y1133574D01*
X184208Y1133908D01*
X183808Y1133974D01*
X183341Y1133841D01*
X183008Y1133374D01*
X182875Y1132908D01*
Y1132308D01*
G01Y1132908D02*
X182675Y1133308D01*
X182341Y1133641D01*
X181941Y1133774D01*
X181541Y1133641D01*
X181208Y1133308D01*
X181008Y1132708D01*
X181075Y1132108D01*
X181341Y1131508D01*
G01X181675Y1135774D02*
X181275Y1136174D01*
X181075Y1136641D01*
X181008Y1137174D01*
X181141Y1137841D01*
X181475Y1138308D01*
X181875Y1138441D01*
X182275Y1138374D01*
X182608Y1138108D01*
X183275Y1136774D01*
X183741Y1136174D01*
X184408Y1135774D01*
X185008Y1135641D01*
Y1138441D01*
G01Y1140241D02*
X181008Y1143041D01*
G01Y1140241D02*
X185008Y1143041D01*
G01Y1146108D02*
X184141Y1146241D01*
X183408Y1146441D01*
X182741Y1146708D01*
X182008Y1147041D01*
X181008Y1147574D01*
Y1144908D01*
G01X184408Y1149374D02*
X184741Y1149774D01*
X184941Y1150241D01*
X185008Y1150841D01*
X184875Y1151441D01*
X184608Y1151908D01*
X184141Y1152241D01*
X183608Y1152308D01*
X183075Y1152174D01*
X182741Y1151841D01*
X182475Y1151374D01*
X182408Y1150908D01*
X182475Y1150441D01*
X182741Y1149841D01*
X181008Y1150041D01*
Y1151841D01*
G01X183208Y1408486D02*
X183675Y1408886D01*
X183941Y1409420D01*
X184008Y1410020D01*
X183941Y1410553D01*
X183608Y1411086D01*
X183208Y1411420D01*
X182808Y1411486D01*
X182341Y1411353D01*
X182008Y1410886D01*
X181875Y1410420D01*
Y1409820D01*
G01Y1410420D02*
X181675Y1410820D01*
X181341Y1411153D01*
X180941Y1411286D01*
X180541Y1411153D01*
X180208Y1410820D01*
X180008Y1410220D01*
X180075Y1409620D01*
X180341Y1409020D01*
G01X180675Y1413286D02*
X180275Y1413686D01*
X180075Y1414153D01*
X180008Y1414686D01*
X180141Y1415353D01*
X180475Y1415820D01*
X180875Y1415953D01*
X181275Y1415886D01*
X181608Y1415620D01*
X182275Y1414286D01*
X182741Y1413686D01*
X183408Y1413286D01*
X184008Y1413153D01*
Y1415953D01*
G01Y1417753D02*
X180008Y1420553D01*
G01Y1417753D02*
X184008Y1420553D01*
G01Y1423620D02*
X183141Y1423753D01*
X182408Y1423953D01*
X181741Y1424220D01*
X181008Y1424553D01*
X180008Y1425086D01*
Y1422420D01*
G01X183408Y1426886D02*
X183741Y1427286D01*
X183941Y1427753D01*
X184008Y1428353D01*
X183875Y1428953D01*
X183608Y1429420D01*
X183141Y1429753D01*
X182608Y1429820D01*
X182075Y1429686D01*
X181741Y1429353D01*
X181475Y1428886D01*
X181408Y1428420D01*
X181475Y1427953D01*
X181741Y1427353D01*
X180008Y1427553D01*
Y1429353D01*
G01X184208Y1536486D02*
X184675Y1536886D01*
X184941Y1537420D01*
X185008Y1538020D01*
X184941Y1538553D01*
X184608Y1539086D01*
X184208Y1539420D01*
X183808Y1539486D01*
X183341Y1539353D01*
X183008Y1538886D01*
X182875Y1538420D01*
Y1537820D01*
G01Y1538420D02*
X182675Y1538820D01*
X182341Y1539153D01*
X181941Y1539286D01*
X181541Y1539153D01*
X181208Y1538820D01*
X181008Y1538220D01*
X181075Y1537620D01*
X181341Y1537020D01*
G01X181675Y1541286D02*
X181275Y1541686D01*
X181075Y1542153D01*
X181008Y1542686D01*
X181141Y1543353D01*
X181475Y1543820D01*
X181875Y1543953D01*
X182275Y1543886D01*
X182608Y1543620D01*
X183275Y1542286D01*
X183741Y1541686D01*
X184408Y1541286D01*
X185008Y1541153D01*
Y1543953D01*
G01Y1545753D02*
X181008Y1548553D01*
G01Y1545753D02*
X185008Y1548553D01*
G01Y1551620D02*
X184141Y1551753D01*
X183408Y1551953D01*
X182741Y1552220D01*
X182008Y1552553D01*
X181008Y1553086D01*
Y1550420D01*
G01X184408Y1554886D02*
X184741Y1555286D01*
X184941Y1555753D01*
X185008Y1556353D01*
X184875Y1556953D01*
X184608Y1557420D01*
X184141Y1557753D01*
X183608Y1557820D01*
X183075Y1557686D01*
X182741Y1557353D01*
X182475Y1556886D01*
X182408Y1556420D01*
X182475Y1555953D01*
X182741Y1555353D01*
X181008Y1555553D01*
Y1557353D01*
G01X183208Y1813998D02*
X183675Y1814398D01*
X183941Y1814932D01*
X184008Y1815532D01*
X183941Y1816065D01*
X183608Y1816598D01*
X183208Y1816932D01*
X182808Y1816998D01*
X182341Y1816865D01*
X182008Y1816398D01*
X181875Y1815932D01*
Y1815332D01*
G01Y1815932D02*
X181675Y1816332D01*
X181341Y1816665D01*
X180941Y1816798D01*
X180541Y1816665D01*
X180208Y1816332D01*
X180008Y1815732D01*
X180075Y1815132D01*
X180341Y1814532D01*
G01X180675Y1818798D02*
X180275Y1819198D01*
X180075Y1819665D01*
X180008Y1820198D01*
X180141Y1820865D01*
X180475Y1821332D01*
X180875Y1821465D01*
X181275Y1821398D01*
X181608Y1821132D01*
X182275Y1819798D01*
X182741Y1819198D01*
X183408Y1818798D01*
X184008Y1818665D01*
Y1821465D01*
G01Y1823265D02*
X180008Y1826065D01*
G01Y1823265D02*
X184008Y1826065D01*
G01Y1829132D02*
X183141Y1829265D01*
X182408Y1829465D01*
X181741Y1829732D01*
X181008Y1830065D01*
X180008Y1830598D01*
Y1827932D01*
G01X183408Y1832398D02*
X183741Y1832798D01*
X183941Y1833265D01*
X184008Y1833865D01*
X183875Y1834465D01*
X183608Y1834932D01*
X183141Y1835265D01*
X182608Y1835332D01*
X182075Y1835198D01*
X181741Y1834865D01*
X181475Y1834398D01*
X181408Y1833932D01*
X181475Y1833465D01*
X181741Y1832865D01*
X180008Y1833065D01*
Y1834865D01*
G01X184208Y1941998D02*
X184675Y1942398D01*
X184941Y1942932D01*
X185008Y1943532D01*
X184941Y1944065D01*
X184608Y1944598D01*
X184208Y1944932D01*
X183808Y1944998D01*
X183341Y1944865D01*
X183008Y1944398D01*
X182875Y1943932D01*
Y1943332D01*
G01Y1943932D02*
X182675Y1944332D01*
X182341Y1944665D01*
X181941Y1944798D01*
X181541Y1944665D01*
X181208Y1944332D01*
X181008Y1943732D01*
X181075Y1943132D01*
X181341Y1942532D01*
G01X181675Y1946798D02*
X181275Y1947198D01*
X181075Y1947665D01*
X181008Y1948198D01*
X181141Y1948865D01*
X181475Y1949332D01*
X181875Y1949465D01*
X182275Y1949398D01*
X182608Y1949132D01*
X183275Y1947798D01*
X183741Y1947198D01*
X184408Y1946798D01*
X185008Y1946665D01*
Y1949465D01*
G01Y1951265D02*
X181008Y1954065D01*
G01Y1951265D02*
X185008Y1954065D01*
G01Y1957132D02*
X184141Y1957265D01*
X183408Y1957465D01*
X182741Y1957732D01*
X182008Y1958065D01*
X181008Y1958598D01*
Y1955932D01*
G01X184408Y1960398D02*
X184741Y1960798D01*
X184941Y1961265D01*
X185008Y1961865D01*
X184875Y1962465D01*
X184608Y1962932D01*
X184141Y1963265D01*
X183608Y1963332D01*
X183075Y1963198D01*
X182741Y1962865D01*
X182475Y1962398D01*
X182408Y1961932D01*
X182475Y1961465D01*
X182741Y1960865D01*
X181008Y1961065D01*
Y1962865D01*
G01X286991Y263078D02*
Y267078D01*
X286191Y266278D01*
G01Y263078D02*
X287791D01*
G01X290458Y263545D02*
X290924Y263211D01*
X291458Y263078D01*
X291991Y263211D01*
X292458Y263611D01*
X292791Y264211D01*
X292924Y264811D01*
Y265545D01*
X292791Y266145D01*
X292458Y266678D01*
X292058Y266945D01*
X291591Y267078D01*
X291058Y266945D01*
X290658Y266678D01*
X290391Y266278D01*
X290258Y265745D01*
X290391Y265278D01*
X290724Y264811D01*
X291124Y264545D01*
X291591Y264478D01*
X292124Y264611D01*
X292524Y264945D01*
X292924Y265545D01*
G01X296058Y263078D02*
X296191Y263945D01*
X296391Y264678D01*
X296658Y265345D01*
X296991Y266078D01*
X297524Y267078D01*
X294858D01*
G01X299391Y263078D02*
X302191Y267078D01*
G01X299391D02*
X302191Y263078D01*
G01X304124Y266411D02*
X304524Y266811D01*
X304991Y267011D01*
X305524Y267078D01*
X306191Y266945D01*
X306658Y266611D01*
X306791Y266211D01*
X306724Y265811D01*
X306458Y265478D01*
X305124Y264811D01*
X304524Y264345D01*
X304124Y263678D01*
X303991Y263078D01*
X306791D01*
G01X308858Y263545D02*
X309324Y263211D01*
X309858Y263078D01*
X310391Y263211D01*
X310858Y263611D01*
X311191Y264211D01*
X311324Y264811D01*
Y265545D01*
X311191Y266145D01*
X310858Y266678D01*
X310458Y266945D01*
X309991Y267078D01*
X309458Y266945D01*
X309058Y266678D01*
X308791Y266278D01*
X308658Y265745D01*
X308791Y265278D01*
X309124Y264811D01*
X309524Y264545D01*
X309991Y264478D01*
X310524Y264611D01*
X310924Y264945D01*
X311324Y265545D01*
G01X313324Y264745D02*
X313791Y265211D01*
X314191Y265478D01*
X314724Y265611D01*
X315191Y265478D01*
X315524Y265211D01*
X315791Y264811D01*
X315858Y264345D01*
X315791Y263945D01*
X315524Y263545D01*
X315124Y263211D01*
X314658Y263078D01*
X314124Y263211D01*
X313658Y263611D01*
X313391Y264211D01*
X313324Y264878D01*
X313458Y265745D01*
X313658Y266211D01*
X313991Y266678D01*
X314458Y267011D01*
X314924Y267078D01*
X315391Y266945D01*
X315724Y266611D01*
G01X286991Y668580D02*
Y672580D01*
X286191Y671780D01*
G01Y668580D02*
X287791D01*
G01X290458Y669047D02*
X290924Y668713D01*
X291458Y668580D01*
X291991Y668713D01*
X292458Y669113D01*
X292791Y669713D01*
X292924Y670313D01*
Y671047D01*
X292791Y671647D01*
X292458Y672180D01*
X292058Y672447D01*
X291591Y672580D01*
X291058Y672447D01*
X290658Y672180D01*
X290391Y671780D01*
X290258Y671247D01*
X290391Y670780D01*
X290724Y670313D01*
X291124Y670047D01*
X291591Y669980D01*
X292124Y670113D01*
X292524Y670447D01*
X292924Y671047D01*
G01X296058Y668580D02*
X296191Y669447D01*
X296391Y670180D01*
X296658Y670847D01*
X296991Y671580D01*
X297524Y672580D01*
X294858D01*
G01X299391Y668580D02*
X302191Y672580D01*
G01X299391D02*
X302191Y668580D01*
G01X304124Y671913D02*
X304524Y672313D01*
X304991Y672513D01*
X305524Y672580D01*
X306191Y672447D01*
X306658Y672113D01*
X306791Y671713D01*
X306724Y671313D01*
X306458Y670980D01*
X305124Y670313D01*
X304524Y669847D01*
X304124Y669180D01*
X303991Y668580D01*
X306791D01*
G01X308858Y669047D02*
X309324Y668713D01*
X309858Y668580D01*
X310391Y668713D01*
X310858Y669113D01*
X311191Y669713D01*
X311324Y670313D01*
Y671047D01*
X311191Y671647D01*
X310858Y672180D01*
X310458Y672447D01*
X309991Y672580D01*
X309458Y672447D01*
X309058Y672180D01*
X308791Y671780D01*
X308658Y671247D01*
X308791Y670780D01*
X309124Y670313D01*
X309524Y670047D01*
X309991Y669980D01*
X310524Y670113D01*
X310924Y670447D01*
X311324Y671047D01*
G01X313324Y670247D02*
X313791Y670713D01*
X314191Y670980D01*
X314724Y671113D01*
X315191Y670980D01*
X315524Y670713D01*
X315791Y670313D01*
X315858Y669847D01*
X315791Y669447D01*
X315524Y669047D01*
X315124Y668713D01*
X314658Y668580D01*
X314124Y668713D01*
X313658Y669113D01*
X313391Y669713D01*
X313324Y670380D01*
X313458Y671247D01*
X313658Y671713D01*
X313991Y672180D01*
X314458Y672513D01*
X314924Y672580D01*
X315391Y672447D01*
X315724Y672113D01*
G01X286991Y1072123D02*
Y1076123D01*
X286191Y1075323D01*
G01Y1072123D02*
X287791D01*
G01X290458Y1072590D02*
X290924Y1072256D01*
X291458Y1072123D01*
X291991Y1072256D01*
X292458Y1072656D01*
X292791Y1073256D01*
X292924Y1073856D01*
Y1074590D01*
X292791Y1075190D01*
X292458Y1075723D01*
X292058Y1075990D01*
X291591Y1076123D01*
X291058Y1075990D01*
X290658Y1075723D01*
X290391Y1075323D01*
X290258Y1074790D01*
X290391Y1074323D01*
X290724Y1073856D01*
X291124Y1073590D01*
X291591Y1073523D01*
X292124Y1073656D01*
X292524Y1073990D01*
X292924Y1074590D01*
G01X296058Y1072123D02*
X296191Y1072990D01*
X296391Y1073723D01*
X296658Y1074390D01*
X296991Y1075123D01*
X297524Y1076123D01*
X294858D01*
G01X299391Y1072123D02*
X302191Y1076123D01*
G01X299391D02*
X302191Y1072123D01*
G01X304124Y1075456D02*
X304524Y1075856D01*
X304991Y1076056D01*
X305524Y1076123D01*
X306191Y1075990D01*
X306658Y1075656D01*
X306791Y1075256D01*
X306724Y1074856D01*
X306458Y1074523D01*
X305124Y1073856D01*
X304524Y1073390D01*
X304124Y1072723D01*
X303991Y1072123D01*
X306791D01*
G01X308858Y1072590D02*
X309324Y1072256D01*
X309858Y1072123D01*
X310391Y1072256D01*
X310858Y1072656D01*
X311191Y1073256D01*
X311324Y1073856D01*
Y1074590D01*
X311191Y1075190D01*
X310858Y1075723D01*
X310458Y1075990D01*
X309991Y1076123D01*
X309458Y1075990D01*
X309058Y1075723D01*
X308791Y1075323D01*
X308658Y1074790D01*
X308791Y1074323D01*
X309124Y1073856D01*
X309524Y1073590D01*
X309991Y1073523D01*
X310524Y1073656D01*
X310924Y1073990D01*
X311324Y1074590D01*
G01X313324Y1073790D02*
X313791Y1074256D01*
X314191Y1074523D01*
X314724Y1074656D01*
X315191Y1074523D01*
X315524Y1074256D01*
X315791Y1073856D01*
X315858Y1073390D01*
X315791Y1072990D01*
X315524Y1072590D01*
X315124Y1072256D01*
X314658Y1072123D01*
X314124Y1072256D01*
X313658Y1072656D01*
X313391Y1073256D01*
X313324Y1073923D01*
X313458Y1074790D01*
X313658Y1075256D01*
X313991Y1075723D01*
X314458Y1076056D01*
X314924Y1076123D01*
X315391Y1075990D01*
X315724Y1075656D01*
G01X286991Y1887084D02*
Y1891084D01*
X286191Y1890284D01*
G01Y1887084D02*
X287791D01*
G01X290458Y1887551D02*
X290924Y1887217D01*
X291458Y1887084D01*
X291991Y1887217D01*
X292458Y1887617D01*
X292791Y1888217D01*
X292924Y1888817D01*
Y1889551D01*
X292791Y1890151D01*
X292458Y1890684D01*
X292058Y1890951D01*
X291591Y1891084D01*
X291058Y1890951D01*
X290658Y1890684D01*
X290391Y1890284D01*
X290258Y1889751D01*
X290391Y1889284D01*
X290724Y1888817D01*
X291124Y1888551D01*
X291591Y1888484D01*
X292124Y1888617D01*
X292524Y1888951D01*
X292924Y1889551D01*
G01X296058Y1887084D02*
X296191Y1887951D01*
X296391Y1888684D01*
X296658Y1889351D01*
X296991Y1890084D01*
X297524Y1891084D01*
X294858D01*
G01X299391Y1887084D02*
X302191Y1891084D01*
G01X299391D02*
X302191Y1887084D01*
G01X304124Y1890417D02*
X304524Y1890817D01*
X304991Y1891017D01*
X305524Y1891084D01*
X306191Y1890951D01*
X306658Y1890617D01*
X306791Y1890217D01*
X306724Y1889817D01*
X306458Y1889484D01*
X305124Y1888817D01*
X304524Y1888351D01*
X304124Y1887684D01*
X303991Y1887084D01*
X306791D01*
G01X308858Y1887551D02*
X309324Y1887217D01*
X309858Y1887084D01*
X310391Y1887217D01*
X310858Y1887617D01*
X311191Y1888217D01*
X311324Y1888817D01*
Y1889551D01*
X311191Y1890151D01*
X310858Y1890684D01*
X310458Y1890951D01*
X309991Y1891084D01*
X309458Y1890951D01*
X309058Y1890684D01*
X308791Y1890284D01*
X308658Y1889751D01*
X308791Y1889284D01*
X309124Y1888817D01*
X309524Y1888551D01*
X309991Y1888484D01*
X310524Y1888617D01*
X310924Y1888951D01*
X311324Y1889551D01*
G01X313324Y1888751D02*
X313791Y1889217D01*
X314191Y1889484D01*
X314724Y1889617D01*
X315191Y1889484D01*
X315524Y1889217D01*
X315791Y1888817D01*
X315858Y1888351D01*
X315791Y1887951D01*
X315524Y1887551D01*
X315124Y1887217D01*
X314658Y1887084D01*
X314124Y1887217D01*
X313658Y1887617D01*
X313391Y1888217D01*
X313324Y1888884D01*
X313458Y1889751D01*
X313658Y1890217D01*
X313991Y1890684D01*
X314458Y1891017D01*
X314924Y1891084D01*
X315391Y1890951D01*
X315724Y1890617D01*
G01X911554Y191950D02*
X912021Y192350D01*
X912287Y192884D01*
X912354Y193484D01*
X912287Y194017D01*
X911954Y194550D01*
X911554Y194884D01*
X911154Y194950D01*
X910687Y194817D01*
X910354Y194350D01*
X910221Y193884D01*
Y193284D01*
G01Y193884D02*
X910021Y194284D01*
X909687Y194617D01*
X909287Y194750D01*
X908887Y194617D01*
X908554Y194284D01*
X908354Y193684D01*
X908421Y193084D01*
X908687Y192484D01*
G01X909021Y196750D02*
X908621Y197150D01*
X908421Y197617D01*
X908354Y198150D01*
X908487Y198817D01*
X908821Y199284D01*
X909221Y199417D01*
X909621Y199350D01*
X909954Y199084D01*
X910621Y197750D01*
X911087Y197150D01*
X911754Y196750D01*
X912354Y196617D01*
Y199417D01*
G01Y201217D02*
X908354Y204017D01*
G01Y201217D02*
X912354Y204017D01*
G01Y207084D02*
X911487Y207217D01*
X910754Y207417D01*
X910087Y207684D01*
X909354Y208017D01*
X908354Y208550D01*
Y205884D01*
G01X911754Y210350D02*
X912087Y210750D01*
X912287Y211217D01*
X912354Y211817D01*
X912221Y212417D01*
X911954Y212884D01*
X911487Y213217D01*
X910954Y213284D01*
X910421Y213150D01*
X910087Y212817D01*
X909821Y212350D01*
X909754Y211884D01*
X909821Y211417D01*
X910087Y210817D01*
X908354Y211017D01*
Y212817D01*
G01X912554Y319950D02*
X913021Y320350D01*
X913287Y320884D01*
X913354Y321484D01*
X913287Y322017D01*
X912954Y322550D01*
X912554Y322884D01*
X912154Y322950D01*
X911687Y322817D01*
X911354Y322350D01*
X911221Y321884D01*
Y321284D01*
G01Y321884D02*
X911021Y322284D01*
X910687Y322617D01*
X910287Y322750D01*
X909887Y322617D01*
X909554Y322284D01*
X909354Y321684D01*
X909421Y321084D01*
X909687Y320484D01*
G01X910021Y324750D02*
X909621Y325150D01*
X909421Y325617D01*
X909354Y326150D01*
X909487Y326817D01*
X909821Y327284D01*
X910221Y327417D01*
X910621Y327350D01*
X910954Y327084D01*
X911621Y325750D01*
X912087Y325150D01*
X912754Y324750D01*
X913354Y324617D01*
Y327417D01*
G01Y329217D02*
X909354Y332017D01*
G01Y329217D02*
X913354Y332017D01*
G01Y335084D02*
X912487Y335217D01*
X911754Y335417D01*
X911087Y335684D01*
X910354Y336017D01*
X909354Y336550D01*
Y333884D01*
G01X912754Y338350D02*
X913087Y338750D01*
X913287Y339217D01*
X913354Y339817D01*
X913221Y340417D01*
X912954Y340884D01*
X912487Y341217D01*
X911954Y341284D01*
X911421Y341150D01*
X911087Y340817D01*
X910821Y340350D01*
X910754Y339884D01*
X910821Y339417D01*
X911087Y338817D01*
X909354Y339017D01*
Y340817D01*
G01X911554Y597462D02*
X912021Y597862D01*
X912287Y598396D01*
X912354Y598996D01*
X912287Y599529D01*
X911954Y600062D01*
X911554Y600396D01*
X911154Y600462D01*
X910687Y600329D01*
X910354Y599862D01*
X910221Y599396D01*
Y598796D01*
G01Y599396D02*
X910021Y599796D01*
X909687Y600129D01*
X909287Y600262D01*
X908887Y600129D01*
X908554Y599796D01*
X908354Y599196D01*
X908421Y598596D01*
X908687Y597996D01*
G01X909021Y602262D02*
X908621Y602662D01*
X908421Y603129D01*
X908354Y603662D01*
X908487Y604329D01*
X908821Y604796D01*
X909221Y604929D01*
X909621Y604862D01*
X909954Y604596D01*
X910621Y603262D01*
X911087Y602662D01*
X911754Y602262D01*
X912354Y602129D01*
Y604929D01*
G01Y606729D02*
X908354Y609529D01*
G01Y606729D02*
X912354Y609529D01*
G01Y612596D02*
X911487Y612729D01*
X910754Y612929D01*
X910087Y613196D01*
X909354Y613529D01*
X908354Y614062D01*
Y611396D01*
G01X911754Y615862D02*
X912087Y616262D01*
X912287Y616729D01*
X912354Y617329D01*
X912221Y617929D01*
X911954Y618396D01*
X911487Y618729D01*
X910954Y618796D01*
X910421Y618662D01*
X910087Y618329D01*
X909821Y617862D01*
X909754Y617396D01*
X909821Y616929D01*
X910087Y616329D01*
X908354Y616529D01*
Y618329D01*
G01X912554Y725462D02*
X913021Y725862D01*
X913287Y726396D01*
X913354Y726996D01*
X913287Y727529D01*
X912954Y728062D01*
X912554Y728396D01*
X912154Y728462D01*
X911687Y728329D01*
X911354Y727862D01*
X911221Y727396D01*
Y726796D01*
G01Y727396D02*
X911021Y727796D01*
X910687Y728129D01*
X910287Y728262D01*
X909887Y728129D01*
X909554Y727796D01*
X909354Y727196D01*
X909421Y726596D01*
X909687Y725996D01*
G01X910021Y730262D02*
X909621Y730662D01*
X909421Y731129D01*
X909354Y731662D01*
X909487Y732329D01*
X909821Y732796D01*
X910221Y732929D01*
X910621Y732862D01*
X910954Y732596D01*
X911621Y731262D01*
X912087Y730662D01*
X912754Y730262D01*
X913354Y730129D01*
Y732929D01*
G01Y734729D02*
X909354Y737529D01*
G01Y734729D02*
X913354Y737529D01*
G01Y740596D02*
X912487Y740729D01*
X911754Y740929D01*
X911087Y741196D01*
X910354Y741529D01*
X909354Y742062D01*
Y739396D01*
G01X912754Y743862D02*
X913087Y744262D01*
X913287Y744729D01*
X913354Y745329D01*
X913221Y745929D01*
X912954Y746396D01*
X912487Y746729D01*
X911954Y746796D01*
X911421Y746662D01*
X911087Y746329D01*
X910821Y745862D01*
X910754Y745396D01*
X910821Y744929D01*
X911087Y744329D01*
X909354Y744529D01*
Y746329D01*
G01X911554Y1002974D02*
X912021Y1003374D01*
X912287Y1003908D01*
X912354Y1004508D01*
X912287Y1005041D01*
X911954Y1005574D01*
X911554Y1005908D01*
X911154Y1005974D01*
X910687Y1005841D01*
X910354Y1005374D01*
X910221Y1004908D01*
Y1004308D01*
G01Y1004908D02*
X910021Y1005308D01*
X909687Y1005641D01*
X909287Y1005774D01*
X908887Y1005641D01*
X908554Y1005308D01*
X908354Y1004708D01*
X908421Y1004108D01*
X908687Y1003508D01*
G01X909021Y1007774D02*
X908621Y1008174D01*
X908421Y1008641D01*
X908354Y1009174D01*
X908487Y1009841D01*
X908821Y1010308D01*
X909221Y1010441D01*
X909621Y1010374D01*
X909954Y1010108D01*
X910621Y1008774D01*
X911087Y1008174D01*
X911754Y1007774D01*
X912354Y1007641D01*
Y1010441D01*
G01Y1012241D02*
X908354Y1015041D01*
G01Y1012241D02*
X912354Y1015041D01*
G01Y1018108D02*
X911487Y1018241D01*
X910754Y1018441D01*
X910087Y1018708D01*
X909354Y1019041D01*
X908354Y1019574D01*
Y1016908D01*
G01X911754Y1021374D02*
X912087Y1021774D01*
X912287Y1022241D01*
X912354Y1022841D01*
X912221Y1023441D01*
X911954Y1023908D01*
X911487Y1024241D01*
X910954Y1024308D01*
X910421Y1024174D01*
X910087Y1023841D01*
X909821Y1023374D01*
X909754Y1022908D01*
X909821Y1022441D01*
X910087Y1021841D01*
X908354Y1022041D01*
Y1023841D01*
G01X912554Y1130974D02*
X913021Y1131374D01*
X913287Y1131908D01*
X913354Y1132508D01*
X913287Y1133041D01*
X912954Y1133574D01*
X912554Y1133908D01*
X912154Y1133974D01*
X911687Y1133841D01*
X911354Y1133374D01*
X911221Y1132908D01*
Y1132308D01*
G01Y1132908D02*
X911021Y1133308D01*
X910687Y1133641D01*
X910287Y1133774D01*
X909887Y1133641D01*
X909554Y1133308D01*
X909354Y1132708D01*
X909421Y1132108D01*
X909687Y1131508D01*
G01X910021Y1135774D02*
X909621Y1136174D01*
X909421Y1136641D01*
X909354Y1137174D01*
X909487Y1137841D01*
X909821Y1138308D01*
X910221Y1138441D01*
X910621Y1138374D01*
X910954Y1138108D01*
X911621Y1136774D01*
X912087Y1136174D01*
X912754Y1135774D01*
X913354Y1135641D01*
Y1138441D01*
G01Y1140241D02*
X909354Y1143041D01*
G01Y1140241D02*
X913354Y1143041D01*
G01Y1146108D02*
X912487Y1146241D01*
X911754Y1146441D01*
X911087Y1146708D01*
X910354Y1147041D01*
X909354Y1147574D01*
Y1144908D01*
G01X912754Y1149374D02*
X913087Y1149774D01*
X913287Y1150241D01*
X913354Y1150841D01*
X913221Y1151441D01*
X912954Y1151908D01*
X912487Y1152241D01*
X911954Y1152308D01*
X911421Y1152174D01*
X911087Y1151841D01*
X910821Y1151374D01*
X910754Y1150908D01*
X910821Y1150441D01*
X911087Y1149841D01*
X909354Y1150041D01*
Y1151841D01*
G01X911554Y1408486D02*
X912021Y1408886D01*
X912287Y1409420D01*
X912354Y1410020D01*
X912287Y1410553D01*
X911954Y1411086D01*
X911554Y1411420D01*
X911154Y1411486D01*
X910687Y1411353D01*
X910354Y1410886D01*
X910221Y1410420D01*
Y1409820D01*
G01Y1410420D02*
X910021Y1410820D01*
X909687Y1411153D01*
X909287Y1411286D01*
X908887Y1411153D01*
X908554Y1410820D01*
X908354Y1410220D01*
X908421Y1409620D01*
X908687Y1409020D01*
G01X909021Y1413286D02*
X908621Y1413686D01*
X908421Y1414153D01*
X908354Y1414686D01*
X908487Y1415353D01*
X908821Y1415820D01*
X909221Y1415953D01*
X909621Y1415886D01*
X909954Y1415620D01*
X910621Y1414286D01*
X911087Y1413686D01*
X911754Y1413286D01*
X912354Y1413153D01*
Y1415953D01*
G01Y1417753D02*
X908354Y1420553D01*
G01Y1417753D02*
X912354Y1420553D01*
G01Y1423620D02*
X911487Y1423753D01*
X910754Y1423953D01*
X910087Y1424220D01*
X909354Y1424553D01*
X908354Y1425086D01*
Y1422420D01*
G01X911754Y1426886D02*
X912087Y1427286D01*
X912287Y1427753D01*
X912354Y1428353D01*
X912221Y1428953D01*
X911954Y1429420D01*
X911487Y1429753D01*
X910954Y1429820D01*
X910421Y1429686D01*
X910087Y1429353D01*
X909821Y1428886D01*
X909754Y1428420D01*
X909821Y1427953D01*
X910087Y1427353D01*
X908354Y1427553D01*
Y1429353D01*
G01X912554Y1536486D02*
X913021Y1536886D01*
X913287Y1537420D01*
X913354Y1538020D01*
X913287Y1538553D01*
X912954Y1539086D01*
X912554Y1539420D01*
X912154Y1539486D01*
X911687Y1539353D01*
X911354Y1538886D01*
X911221Y1538420D01*
Y1537820D01*
G01Y1538420D02*
X911021Y1538820D01*
X910687Y1539153D01*
X910287Y1539286D01*
X909887Y1539153D01*
X909554Y1538820D01*
X909354Y1538220D01*
X909421Y1537620D01*
X909687Y1537020D01*
G01X910021Y1541286D02*
X909621Y1541686D01*
X909421Y1542153D01*
X909354Y1542686D01*
X909487Y1543353D01*
X909821Y1543820D01*
X910221Y1543953D01*
X910621Y1543886D01*
X910954Y1543620D01*
X911621Y1542286D01*
X912087Y1541686D01*
X912754Y1541286D01*
X913354Y1541153D01*
Y1543953D01*
G01Y1545753D02*
X909354Y1548553D01*
G01Y1545753D02*
X913354Y1548553D01*
G01Y1551620D02*
X912487Y1551753D01*
X911754Y1551953D01*
X911087Y1552220D01*
X910354Y1552553D01*
X909354Y1553086D01*
Y1550420D01*
G01X912754Y1554886D02*
X913087Y1555286D01*
X913287Y1555753D01*
X913354Y1556353D01*
X913221Y1556953D01*
X912954Y1557420D01*
X912487Y1557753D01*
X911954Y1557820D01*
X911421Y1557686D01*
X911087Y1557353D01*
X910821Y1556886D01*
X910754Y1556420D01*
X910821Y1555953D01*
X911087Y1555353D01*
X909354Y1555553D01*
Y1557353D01*
G01X911554Y1813998D02*
X912021Y1814398D01*
X912287Y1814932D01*
X912354Y1815532D01*
X912287Y1816065D01*
X911954Y1816598D01*
X911554Y1816932D01*
X911154Y1816998D01*
X910687Y1816865D01*
X910354Y1816398D01*
X910221Y1815932D01*
Y1815332D01*
G01Y1815932D02*
X910021Y1816332D01*
X909687Y1816665D01*
X909287Y1816798D01*
X908887Y1816665D01*
X908554Y1816332D01*
X908354Y1815732D01*
X908421Y1815132D01*
X908687Y1814532D01*
G01X909021Y1818798D02*
X908621Y1819198D01*
X908421Y1819665D01*
X908354Y1820198D01*
X908487Y1820865D01*
X908821Y1821332D01*
X909221Y1821465D01*
X909621Y1821398D01*
X909954Y1821132D01*
X910621Y1819798D01*
X911087Y1819198D01*
X911754Y1818798D01*
X912354Y1818665D01*
Y1821465D01*
G01Y1823265D02*
X908354Y1826065D01*
G01Y1823265D02*
X912354Y1826065D01*
G01Y1829132D02*
X911487Y1829265D01*
X910754Y1829465D01*
X910087Y1829732D01*
X909354Y1830065D01*
X908354Y1830598D01*
Y1827932D01*
G01X911754Y1832398D02*
X912087Y1832798D01*
X912287Y1833265D01*
X912354Y1833865D01*
X912221Y1834465D01*
X911954Y1834932D01*
X911487Y1835265D01*
X910954Y1835332D01*
X910421Y1835198D01*
X910087Y1834865D01*
X909821Y1834398D01*
X909754Y1833932D01*
X909821Y1833465D01*
X910087Y1832865D01*
X908354Y1833065D01*
Y1834865D01*
G01X912554Y1941998D02*
X913021Y1942398D01*
X913287Y1942932D01*
X913354Y1943532D01*
X913287Y1944065D01*
X912954Y1944598D01*
X912554Y1944932D01*
X912154Y1944998D01*
X911687Y1944865D01*
X911354Y1944398D01*
X911221Y1943932D01*
Y1943332D01*
G01Y1943932D02*
X911021Y1944332D01*
X910687Y1944665D01*
X910287Y1944798D01*
X909887Y1944665D01*
X909554Y1944332D01*
X909354Y1943732D01*
X909421Y1943132D01*
X909687Y1942532D01*
G01X910021Y1946798D02*
X909621Y1947198D01*
X909421Y1947665D01*
X909354Y1948198D01*
X909487Y1948865D01*
X909821Y1949332D01*
X910221Y1949465D01*
X910621Y1949398D01*
X910954Y1949132D01*
X911621Y1947798D01*
X912087Y1947198D01*
X912754Y1946798D01*
X913354Y1946665D01*
Y1949465D01*
G01Y1951265D02*
X909354Y1954065D01*
G01Y1951265D02*
X913354Y1954065D01*
G01Y1957132D02*
X912487Y1957265D01*
X911754Y1957465D01*
X911087Y1957732D01*
X910354Y1958065D01*
X909354Y1958598D01*
Y1955932D01*
G01X912754Y1960398D02*
X913087Y1960798D01*
X913287Y1961265D01*
X913354Y1961865D01*
X913221Y1962465D01*
X912954Y1962932D01*
X912487Y1963265D01*
X911954Y1963332D01*
X911421Y1963198D01*
X911087Y1962865D01*
X910821Y1962398D01*
X910754Y1961932D01*
X910821Y1961465D01*
X911087Y1960865D01*
X909354Y1961065D01*
Y1962865D01*
G01X1045276Y0D02*
X1112953D01*
G03X1127953Y15000I0J15000D01*
G01Y493259D01*
G01X1045276Y25827D02*
G03X1037402I-3937J0D01*
G01X1045276Y0D02*
Y25827D01*
G01X1037402Y56535D02*
G03X1045276I3937J0D01*
G01D02*
Y284882D01*
G01X1009431Y146926D02*
Y150926D01*
X1008631Y150126D01*
G01Y146926D02*
X1010231D01*
G01X1012898Y147393D02*
X1013364Y147059D01*
X1013898Y146926D01*
X1014431Y147059D01*
X1014898Y147459D01*
X1015231Y148059D01*
X1015364Y148659D01*
Y149393D01*
X1015231Y149993D01*
X1014898Y150526D01*
X1014498Y150793D01*
X1014031Y150926D01*
X1013498Y150793D01*
X1013098Y150526D01*
X1012831Y150126D01*
X1012698Y149593D01*
X1012831Y149126D01*
X1013164Y148659D01*
X1013564Y148393D01*
X1014031Y148326D01*
X1014564Y148459D01*
X1014964Y148793D01*
X1015364Y149393D01*
G01X1018498Y146926D02*
X1018631Y147793D01*
X1018831Y148526D01*
X1019098Y149193D01*
X1019431Y149926D01*
X1019964Y150926D01*
X1017298D01*
G01X1021831Y146926D02*
X1024631Y150926D01*
G01X1021831D02*
X1024631Y146926D01*
G01X1026564Y150259D02*
X1026964Y150659D01*
X1027431Y150859D01*
X1027964Y150926D01*
X1028631Y150793D01*
X1029098Y150459D01*
X1029231Y150059D01*
X1029164Y149659D01*
X1028898Y149326D01*
X1027564Y148659D01*
X1026964Y148193D01*
X1026564Y147526D01*
X1026431Y146926D01*
X1029231D01*
G01X1031298Y147393D02*
X1031764Y147059D01*
X1032298Y146926D01*
X1032831Y147059D01*
X1033298Y147459D01*
X1033631Y148059D01*
X1033764Y148659D01*
Y149393D01*
X1033631Y149993D01*
X1033298Y150526D01*
X1032898Y150793D01*
X1032431Y150926D01*
X1031898Y150793D01*
X1031498Y150526D01*
X1031231Y150126D01*
X1031098Y149593D01*
X1031231Y149126D01*
X1031564Y148659D01*
X1031964Y148393D01*
X1032431Y148326D01*
X1032964Y148459D01*
X1033364Y148793D01*
X1033764Y149393D01*
G01X1035764Y148593D02*
X1036231Y149059D01*
X1036631Y149326D01*
X1037164Y149459D01*
X1037631Y149326D01*
X1037964Y149059D01*
X1038231Y148659D01*
X1038298Y148193D01*
X1038231Y147793D01*
X1037964Y147393D01*
X1037564Y147059D01*
X1037098Y146926D01*
X1036564Y147059D01*
X1036098Y147459D01*
X1035831Y148059D01*
X1035764Y148726D01*
X1035898Y149593D01*
X1036098Y150059D01*
X1036431Y150526D01*
X1036898Y150859D01*
X1037364Y150926D01*
X1037831Y150793D01*
X1038164Y150459D01*
G01X1037402Y315591D02*
G03X1045276I3937J0D01*
G01Y284882D02*
G03X1037402I-3937J0D01*
G01X1045276Y315591D02*
Y543937D01*
G01D02*
G03X1037402I-3937J0D01*
G01Y574646D02*
G03X1045276I3937J0D01*
G01D02*
Y802992D01*
G01X1009431Y670548D02*
Y674548D01*
X1008631Y673748D01*
G01Y670548D02*
X1010231D01*
G01X1012898Y671015D02*
X1013364Y670681D01*
X1013898Y670548D01*
X1014431Y670681D01*
X1014898Y671081D01*
X1015231Y671681D01*
X1015364Y672281D01*
Y673015D01*
X1015231Y673615D01*
X1014898Y674148D01*
X1014498Y674415D01*
X1014031Y674548D01*
X1013498Y674415D01*
X1013098Y674148D01*
X1012831Y673748D01*
X1012698Y673215D01*
X1012831Y672748D01*
X1013164Y672281D01*
X1013564Y672015D01*
X1014031Y671948D01*
X1014564Y672081D01*
X1014964Y672415D01*
X1015364Y673015D01*
G01X1018498Y670548D02*
X1018631Y671415D01*
X1018831Y672148D01*
X1019098Y672815D01*
X1019431Y673548D01*
X1019964Y674548D01*
X1017298D01*
G01X1021831Y670548D02*
X1024631Y674548D01*
G01X1021831D02*
X1024631Y670548D01*
G01X1026564Y673881D02*
X1026964Y674281D01*
X1027431Y674481D01*
X1027964Y674548D01*
X1028631Y674415D01*
X1029098Y674081D01*
X1029231Y673681D01*
X1029164Y673281D01*
X1028898Y672948D01*
X1027564Y672281D01*
X1026964Y671815D01*
X1026564Y671148D01*
X1026431Y670548D01*
X1029231D01*
G01X1031298Y671015D02*
X1031764Y670681D01*
X1032298Y670548D01*
X1032831Y670681D01*
X1033298Y671081D01*
X1033631Y671681D01*
X1033764Y672281D01*
Y673015D01*
X1033631Y673615D01*
X1033298Y674148D01*
X1032898Y674415D01*
X1032431Y674548D01*
X1031898Y674415D01*
X1031498Y674148D01*
X1031231Y673748D01*
X1031098Y673215D01*
X1031231Y672748D01*
X1031564Y672281D01*
X1031964Y672015D01*
X1032431Y671948D01*
X1032964Y672081D01*
X1033364Y672415D01*
X1033764Y673015D01*
G01X1035764Y672215D02*
X1036231Y672681D01*
X1036631Y672948D01*
X1037164Y673081D01*
X1037631Y672948D01*
X1037964Y672681D01*
X1038231Y672281D01*
X1038298Y671815D01*
X1038231Y671415D01*
X1037964Y671015D01*
X1037564Y670681D01*
X1037098Y670548D01*
X1036564Y670681D01*
X1036098Y671081D01*
X1035831Y671681D01*
X1035764Y672348D01*
X1035898Y673215D01*
X1036098Y673681D01*
X1036431Y674148D01*
X1036898Y674481D01*
X1037364Y674548D01*
X1037831Y674415D01*
X1038164Y674081D01*
G01X1037402Y833701D02*
G03X1045276I3937J0D01*
G01Y802992D02*
G03X1037402I-3937J0D01*
G01X1045276Y833701D02*
Y1062047D01*
G01D02*
G03X1037402I-3937J0D01*
G01X1009431Y1066217D02*
Y1070217D01*
X1008631Y1069417D01*
G01Y1066217D02*
X1010231D01*
G01X1012898Y1066684D02*
X1013364Y1066350D01*
X1013898Y1066217D01*
X1014431Y1066350D01*
X1014898Y1066750D01*
X1015231Y1067350D01*
X1015364Y1067950D01*
Y1068684D01*
X1015231Y1069284D01*
X1014898Y1069817D01*
X1014498Y1070084D01*
X1014031Y1070217D01*
X1013498Y1070084D01*
X1013098Y1069817D01*
X1012831Y1069417D01*
X1012698Y1068884D01*
X1012831Y1068417D01*
X1013164Y1067950D01*
X1013564Y1067684D01*
X1014031Y1067617D01*
X1014564Y1067750D01*
X1014964Y1068084D01*
X1015364Y1068684D01*
G01X1018498Y1066217D02*
X1018631Y1067084D01*
X1018831Y1067817D01*
X1019098Y1068484D01*
X1019431Y1069217D01*
X1019964Y1070217D01*
X1017298D01*
G01X1021831Y1066217D02*
X1024631Y1070217D01*
G01X1021831D02*
X1024631Y1066217D01*
G01X1026564Y1069550D02*
X1026964Y1069950D01*
X1027431Y1070150D01*
X1027964Y1070217D01*
X1028631Y1070084D01*
X1029098Y1069750D01*
X1029231Y1069350D01*
X1029164Y1068950D01*
X1028898Y1068617D01*
X1027564Y1067950D01*
X1026964Y1067484D01*
X1026564Y1066817D01*
X1026431Y1066217D01*
X1029231D01*
G01X1031298Y1066684D02*
X1031764Y1066350D01*
X1032298Y1066217D01*
X1032831Y1066350D01*
X1033298Y1066750D01*
X1033631Y1067350D01*
X1033764Y1067950D01*
Y1068684D01*
X1033631Y1069284D01*
X1033298Y1069817D01*
X1032898Y1070084D01*
X1032431Y1070217D01*
X1031898Y1070084D01*
X1031498Y1069817D01*
X1031231Y1069417D01*
X1031098Y1068884D01*
X1031231Y1068417D01*
X1031564Y1067950D01*
X1031964Y1067684D01*
X1032431Y1067617D01*
X1032964Y1067750D01*
X1033364Y1068084D01*
X1033764Y1068684D01*
G01X1035764Y1067884D02*
X1036231Y1068350D01*
X1036631Y1068617D01*
X1037164Y1068750D01*
X1037631Y1068617D01*
X1037964Y1068350D01*
X1038231Y1067950D01*
X1038298Y1067484D01*
X1038231Y1067084D01*
X1037964Y1066684D01*
X1037564Y1066350D01*
X1037098Y1066217D01*
X1036564Y1066350D01*
X1036098Y1066750D01*
X1035831Y1067350D01*
X1035764Y1068017D01*
X1035898Y1068884D01*
X1036098Y1069350D01*
X1036431Y1069817D01*
X1036898Y1070150D01*
X1037364Y1070217D01*
X1037831Y1070084D01*
X1038164Y1069750D01*
G01X1037402Y1092756D02*
G03X1045276I3937J0D01*
G01D02*
Y1321102D01*
G01D02*
G03X1037402I-3937J0D01*
G01Y1351811D02*
G03X1045276I3937J0D01*
G01D02*
Y1377638D01*
G01X1037401Y1397976D02*
Y1424882D01*
X1033464Y1428819D01*
X1028149D01*
G02X1023228Y1433740I0J4921D01*
G01Y1610886D01*
X1022244Y1611870D01*
X993681D01*
G02Y1616082I0J2106D01*
G01X1022244D01*
X1023228Y1617066D01*
Y1676496D01*
G02X1028149Y1681417I4921J0D01*
G01X1033464D01*
X1037401Y1685354D01*
Y1712976D01*
G01X1045276Y1377638D02*
X1112953D01*
G02X1127953Y1362638I0J-15000D01*
G01Y501133D01*
G01X1042745Y1545726D02*
X1043078Y1546259D01*
X1043278Y1546859D01*
Y1547393D01*
X1043078Y1547926D01*
X1042745Y1548326D01*
X1042278Y1548526D01*
X1041811Y1548393D01*
X1041411Y1548059D01*
X1041145Y1547459D01*
X1041011Y1546659D01*
X1040745Y1546193D01*
X1040278Y1545993D01*
X1039811Y1546126D01*
X1039478Y1546459D01*
X1039278Y1546926D01*
Y1547393D01*
X1039411Y1547859D01*
X1039745Y1548259D01*
G01X1043278Y1551726D02*
X1039278D01*
G01X1040611Y1556326D02*
X1043278D01*
G01X1039545D02*
X1039478Y1556193D01*
X1039345D01*
X1039278Y1556326D01*
X1039345Y1556459D01*
X1039478D01*
X1039545Y1556326D01*
G01X1039278Y1560926D02*
X1043278D01*
G01X1040611Y1559993D02*
Y1561859D01*
G01X1023753Y1553876D02*
X1039728Y1553976D01*
G01X1028744Y1555407D02*
X1023753Y1553876D01*
X1028762Y1552407D01*
X1028744Y1555407D01*
G01X1045276Y1732598D02*
X1112953D01*
G03X1127953Y1747598I0J15000D01*
G01Y1977126D01*
G03X1112953Y1992126I-15000J0D01*
G01X1045276D01*
G01X1037402Y1767835D02*
G03X1045276I3937J0D01*
G01Y1737126D02*
G03X1037402I-3937J0D01*
G01X1045276Y1767835D02*
Y1956890D01*
G01Y1732598D02*
Y1737126D01*
G01X1009431Y1887084D02*
Y1891084D01*
X1008631Y1890284D01*
G01Y1887084D02*
X1010231D01*
G01X1012898Y1887551D02*
X1013364Y1887217D01*
X1013898Y1887084D01*
X1014431Y1887217D01*
X1014898Y1887617D01*
X1015231Y1888217D01*
X1015364Y1888817D01*
Y1889551D01*
X1015231Y1890151D01*
X1014898Y1890684D01*
X1014498Y1890951D01*
X1014031Y1891084D01*
X1013498Y1890951D01*
X1013098Y1890684D01*
X1012831Y1890284D01*
X1012698Y1889751D01*
X1012831Y1889284D01*
X1013164Y1888817D01*
X1013564Y1888551D01*
X1014031Y1888484D01*
X1014564Y1888617D01*
X1014964Y1888951D01*
X1015364Y1889551D01*
G01X1018498Y1887084D02*
X1018631Y1887951D01*
X1018831Y1888684D01*
X1019098Y1889351D01*
X1019431Y1890084D01*
X1019964Y1891084D01*
X1017298D01*
G01X1021831Y1887084D02*
X1024631Y1891084D01*
G01X1021831D02*
X1024631Y1887084D01*
G01X1026564Y1890417D02*
X1026964Y1890817D01*
X1027431Y1891017D01*
X1027964Y1891084D01*
X1028631Y1890951D01*
X1029098Y1890617D01*
X1029231Y1890217D01*
X1029164Y1889817D01*
X1028898Y1889484D01*
X1027564Y1888817D01*
X1026964Y1888351D01*
X1026564Y1887684D01*
X1026431Y1887084D01*
X1029231D01*
G01X1031298Y1887551D02*
X1031764Y1887217D01*
X1032298Y1887084D01*
X1032831Y1887217D01*
X1033298Y1887617D01*
X1033631Y1888217D01*
X1033764Y1888817D01*
Y1889551D01*
X1033631Y1890151D01*
X1033298Y1890684D01*
X1032898Y1890951D01*
X1032431Y1891084D01*
X1031898Y1890951D01*
X1031498Y1890684D01*
X1031231Y1890284D01*
X1031098Y1889751D01*
X1031231Y1889284D01*
X1031564Y1888817D01*
X1031964Y1888551D01*
X1032431Y1888484D01*
X1032964Y1888617D01*
X1033364Y1888951D01*
X1033764Y1889551D01*
G01X1035764Y1888751D02*
X1036231Y1889217D01*
X1036631Y1889484D01*
X1037164Y1889617D01*
X1037631Y1889484D01*
X1037964Y1889217D01*
X1038231Y1888817D01*
X1038298Y1888351D01*
X1038231Y1887951D01*
X1037964Y1887551D01*
X1037564Y1887217D01*
X1037098Y1887084D01*
X1036564Y1887217D01*
X1036098Y1887617D01*
X1035831Y1888217D01*
X1035764Y1888884D01*
X1035898Y1889751D01*
X1036098Y1890217D01*
X1036431Y1890684D01*
X1036898Y1891017D01*
X1037364Y1891084D01*
X1037831Y1890951D01*
X1038164Y1890617D01*
G01X1037402Y1987598D02*
G03X1045276I3937J0D01*
G01Y1956890D02*
G03X1037402I-3937J0D01*
G01X1045276Y1987598D02*
Y1992126D01*
G01X1127953Y501133D02*
G03Y493259I0J-3937D01*
G54D13*
X23426Y281496D03*
X24764Y286496D03*
X28426Y290197D03*
X38465D03*
X42166Y286496D03*
X11615Y1922835D03*
X12953Y1927835D03*
X16615Y1931536D03*
X26654D03*
X30355Y1927835D03*
X31693Y1922835D03*
X43504Y281496D03*
X123819Y17717D03*
X125157Y22717D03*
X128819Y26418D03*
X138858D03*
X142559Y22717D03*
X143897Y17717D03*
X265552Y279528D03*
X266890Y284528D03*
X270552Y288229D03*
X280591D03*
X284292Y284528D03*
X285630Y279528D03*
X265552Y685030D03*
X266890Y690030D03*
X270552Y693731D03*
X280591D03*
X284292Y690030D03*
X285630Y685030D03*
X265552Y1088573D03*
X266890Y1093573D03*
X270552Y1097274D03*
X280591D03*
X284292Y1093573D03*
X285630Y1088573D03*
X265552Y1903534D03*
X266890Y1908534D03*
X270552Y1912235D03*
X280591D03*
X284292Y1908534D03*
X285630Y1903534D03*
X987992Y163376D03*
Y686998D03*
Y1082667D03*
Y1903534D03*
X989330Y168376D03*
X992992Y172077D03*
X1003031D03*
X1006732Y168376D03*
X1008070Y163376D03*
X989330Y691998D03*
X992992Y695699D03*
X1003031D03*
X1006732Y691998D03*
X1008070Y686998D03*
X989330Y1087667D03*
X992992Y1091368D03*
X1003031D03*
X1006732Y1087667D03*
X1008070Y1082667D03*
X989330Y1908534D03*
X992992Y1912235D03*
X1003031D03*
X1006732Y1908534D03*
X1008070Y1903534D03*
X1271996Y333079D03*
G54D14*
X11811Y571426D03*
Y949378D03*
Y1067489D03*
Y1484811D03*
Y1445441D03*
Y1862763D03*
X1271996Y192579D03*
G54D15*
X25000Y988000D03*
X27825Y995000D03*
X78675Y380704D03*
X47500Y660500D03*
X45000Y1057000D03*
X77607Y1565391D03*
X183344Y808200D03*
X126221Y861250D03*
Y853750D03*
X163170Y1210999D03*
X117387Y1536250D03*
Y1543750D03*
X122844Y1672400D03*
X130344D03*
X213244Y23725D03*
X243156Y382060D03*
X235656D03*
X228156Y438500D03*
X220656D03*
X206700Y575000D03*
X190844Y808200D03*
X242700Y1266656D03*
Y1259156D03*
X232344Y1740000D03*
X239844D03*
X284000Y541344D03*
Y548844D03*
X317156Y1193440D03*
X324656D03*
X276344Y1183060D03*
X268844D03*
X401500Y395500D03*
X393500Y422000D03*
X401500Y830000D03*
X393500Y852000D03*
X402000Y1196500D03*
X396637Y1176000D03*
X358156Y1411000D03*
X350656D03*
X402000Y1695000D03*
X379500Y1673750D03*
X427500Y297156D03*
Y304656D03*
X412500Y1130750D03*
Y1138250D03*
X438656Y1669000D03*
X431156D03*
X458156Y1743000D03*
X450656D03*
X512656Y623500D03*
X520156D03*
X555000Y524344D03*
Y531844D03*
X807756Y377775D03*
X808256Y783275D03*
X807756Y1188775D03*
Y1594275D03*
X979500Y1669750D03*
Y1662250D03*
X1271996Y389279D03*
G54D16*
X33469Y1029523D03*
X269690Y1490152D03*
X1271996Y304979D03*
G54D17*
X38800Y1810100D03*
X22100Y1802800D03*
X38317Y1804491D03*
X34900Y1807200D03*
X35100Y1813000D03*
X26500Y1805200D03*
X26600Y1810600D03*
X26300Y1815000D03*
X30800Y1805300D03*
Y1810500D03*
X17500Y1801900D03*
X22000Y1814100D03*
Y1809100D03*
X17500Y1806900D03*
Y1811900D03*
Y1816500D03*
X7600Y1855000D03*
X17500Y1827500D03*
X22600Y1825200D03*
X17500Y1832500D03*
X22500Y1830000D03*
X17500Y1837500D03*
X22500Y1835000D03*
X17500Y1842500D03*
X22500Y1840000D03*
X17500Y1847500D03*
X22500Y1845000D03*
X17500Y1852500D03*
X22500Y1850000D03*
X17500Y1857500D03*
X22500Y1855000D03*
Y1865000D03*
X17500Y1867500D03*
X22500Y1860000D03*
X12500Y1845000D03*
Y1850000D03*
Y1855000D03*
Y1840000D03*
X17500Y1872500D03*
X22500Y1870000D03*
X12500D03*
X71200Y36900D03*
X136100Y41200D03*
X935000Y1425000D03*
X984900Y1430400D03*
X953800Y1424900D03*
X945000Y1425000D03*
X935000Y1455000D03*
Y1475000D03*
Y1445000D03*
Y1465000D03*
Y1435000D03*
X945000Y1475000D03*
X955000D03*
X965000D03*
X945000Y1465000D03*
X955000D03*
X965000D03*
X945000Y1455000D03*
X955000D03*
X965000D03*
X945000Y1445000D03*
X955000D03*
X965000D03*
X945000Y1435000D03*
X955000D03*
X965000D03*
Y1495000D03*
X955000D03*
X935000Y1485000D03*
Y1495000D03*
X945000D03*
Y1485000D03*
X955000D03*
X965000D03*
X975000Y1495000D03*
Y1485000D03*
Y1475000D03*
Y1465000D03*
Y1455000D03*
Y1445000D03*
Y1435000D03*
X965000Y1525000D03*
X955000D03*
X945000D03*
Y1516000D03*
X955000D03*
X965000D03*
X935000Y1555000D03*
X945000D03*
X955000D03*
X965000D03*
X935000Y1575000D03*
Y1565000D03*
X945000Y1575000D03*
X955000D03*
X965000D03*
Y1565000D03*
X955000D03*
X945000D03*
X935000Y1545000D03*
Y1535000D03*
Y1525000D03*
Y1516000D03*
X965000Y1545000D03*
X955000D03*
X945000D03*
Y1535000D03*
X955000D03*
X965000D03*
X975000Y1565000D03*
Y1575000D03*
Y1525000D03*
Y1535000D03*
Y1545000D03*
Y1555000D03*
X935000Y1505000D03*
X955000D03*
X945000D03*
X965000D03*
Y1605000D03*
X935000Y1595000D03*
Y1585000D03*
X945000Y1595000D03*
X955000D03*
X965000D03*
Y1585000D03*
X955000D03*
X945000D03*
X975000Y1595000D03*
Y1605000D03*
Y1585000D03*
X990600Y1427100D03*
X995000Y1425000D03*
X1005000D03*
X1271996Y361179D03*
G54D18*
X72835Y17047D03*
Y190275D03*
Y422559D03*
Y595787D03*
Y828071D03*
Y1001299D03*
Y1233583D03*
Y1406811D03*
Y1639095D03*
Y1812323D03*
X171260Y179803D03*
Y353031D03*
Y585315D03*
Y758543D03*
Y990827D03*
Y1164055D03*
Y1396339D03*
Y1569567D03*
Y1801851D03*
Y1975079D03*
X899606Y179803D03*
Y353031D03*
Y585315D03*
Y758543D03*
Y990827D03*
Y1164055D03*
Y1396339D03*
Y1569567D03*
Y1801851D03*
Y1975079D03*
X1271996Y136379D03*
G54D19*
X82087Y28858D03*
Y178464D03*
Y434370D03*
Y583976D03*
Y839882D03*
Y989488D03*
Y1245394D03*
Y1395000D03*
Y1650906D03*
Y1800512D03*
X162008Y191614D03*
Y341220D03*
Y597126D03*
Y746732D03*
Y1002638D03*
Y1152244D03*
Y1408150D03*
Y1557756D03*
Y1813662D03*
Y1963268D03*
X890354Y191614D03*
Y341220D03*
Y597126D03*
Y746732D03*
Y1002638D03*
Y1152244D03*
Y1408150D03*
Y1557756D03*
Y1813662D03*
Y1963268D03*
X1271996Y248779D03*
M02*
